G04 ================== begin FILE IDENTIFICATION RECORD ==================*
G04 Layout Name:  DA0T6MTH8C0_t6m_tray_bp_c_brd_103112_274.brd*
G04 Film Name:    in1*
G04 File Format:  Gerber RS274X*
G04 File Origin:  Cadence Allegro 16.3-S048*
G04 Origin Date:  Tue Nov 26 11:26:41 2013*
G04 *
G04 Layer:  DRAWING FORMAT/TITLE_BLOCK*
G04 Layer:  VIA CLASS/IN1*
G04 Layer:  PIN/IN1*
G04 Layer:  MANUFACTURING/PHOTOPLOT_OUTLINE*
G04 Layer:  ETCH/IN1*
G04 Layer:  DRAWING FORMAT/TITLE_DATA_IN1*
G04 *
G04 Offset:    (0.00 0.00)*
G04 Mirror:    No*
G04 Mode:      Positive*
G04 Rotation:  0*
G04 FullContactRelief:  No*
G04 UndefLineWidth:     6.00*
G04 ================== end FILE IDENTIFICATION RECORD ====================*
%FSLAX25Y25*MOIN*%
%IR0*IPPOS*OFA0.00000B0.00000*MIA0B0*SFA1.00000B1.00000*%
%ADD14C,.02*%
%ADD13C,.04*%
%ADD19C,.051*%
%ADD17C,.061*%
%ADD18C,.036*%
%ADD12C,.054*%
%ADD11C,.063*%
%ADD16C,.046*%
%ADD21C,.092*%
%ADD10C,.066*%
%ADD22C,.213*%
%ADD15C,.228*%
%ADD20C,.139*%
%ADD23C,.018*%
%ADD24C,.006*%
%ADD25C,.0072*%
%ADD36C,.03004*%
%ADD34C,.05004*%
%ADD38C,.07104*%
%ADD39C,.06304*%
%ADD35C,.06404*%
%ADD33C,.07304*%
%ADD37C,.05604*%
%ADD40C,.05904*%
%ADD26C,.09612*%
%ADD30C,.07608*%
%ADD27C,.09606*%
%ADD32C,.1601*%
%ADD31C,.16024*%
%ADD28C,.11706*%
%ADD29C,.11708*%
G75*
%LPD*%
G75*
G36*
G01X1667000Y45500D02*
X1630500Y9000D01*
X1560995D01*
X1560753Y9151D01*
X1560690Y9280D01*
G03X1560286Y9859I-2068J-1012D01*
G03X1559874Y10200I-1664J-1591D01*
G02Y11848I567J824D01*
G03Y15712I-1252J1932D01*
G02X1559890Y17371I567J824D01*
G03X1560911Y19534I-1268J1921D01*
G02X1561906Y20638I994J104D01*
G01X1567136D01*
X1568368Y19406D01*
X1569384Y18391D01*
X1569422Y18303D01*
G03X1571397Y20278I1378J597D01*
G01X1571309Y20316D01*
X1569933Y21692D01*
X1568264Y23362D01*
X1561894D01*
G02X1560901Y24475I0J1000D01*
G03Y25129I-2279J327D01*
G03X1560658Y25878I-2279J-325D01*
G01X1560600Y25988D01*
Y29130D01*
X1560658Y29240D01*
G03Y31390I-2036J1075D01*
G01X1560600Y31500D01*
Y33100D01*
X1560519D01*
X1560259Y33287D01*
X1560084Y33805D01*
X1560245Y34192D01*
X1560307Y34258D01*
G03X1560505Y37151I-1685J1569D01*
G02X1560457Y37642I409J288D01*
G01X1560634Y38039D01*
X1560900Y38212D01*
Y41007D01*
X1560904Y41040D01*
Y41047D01*
X1560911Y41110D01*
G03X1560912Y41556I-2289J228D01*
G01X1560910Y41577D01*
X1560907Y41609D01*
X1560900Y41671D01*
Y46519D01*
X1560904Y46552D01*
Y46559D01*
X1560911Y46622D01*
G03X1560912Y47068I-2289J228D01*
G01X1560910Y47089D01*
X1560907Y47121D01*
X1560900Y47183D01*
Y49600D01*
X1560639D01*
G02X1560163Y49945I-1J500D01*
G01X1560041Y50321D01*
X1560111Y50600D01*
X1560215Y50700D01*
G03X1557029I-1593J1662D01*
G01X1557133Y50600D01*
X1557203Y50321D01*
X1557081Y49945D01*
G02X1556605Y49600I-475J155D01*
G01X1556500D01*
Y47748D01*
X1556468Y47663D01*
G03Y46039I2154J-812D01*
G01X1556500Y45954D01*
Y42236D01*
X1556468Y42151D01*
G03Y40527I2154J-812D01*
G01X1556500Y40442D01*
Y38200D01*
X1556538D01*
X1556787Y37642D01*
G02X1556739Y37151I-457J-203D01*
G03X1556660Y34623I1883J-1324D01*
G02X1556300Y33230I-852J-523D01*
G01Y23862D01*
G02X1555800Y23362I-500J0D01*
G01X1555736D01*
X1555326Y22952D01*
X1554018D01*
G02X1553028Y24090I0J1000D01*
G03X1552927Y25153I-2280J320D01*
G01X1552900Y25232D01*
Y29100D01*
X1552927Y29179D01*
G03Y30665I-2179J743D01*
G01X1552900Y30744D01*
Y34611D01*
X1552927Y34690D01*
G03Y36176I-2179J743D01*
G01X1552900Y36255D01*
Y37400D01*
X1551951D01*
X1551839Y37460D01*
G03X1551149Y37700I-1092J-2027D01*
G02X1551163Y38681I105J489D01*
G03X1552927Y41688I-415J2264D01*
G01X1552900Y41767D01*
Y43300D01*
X1553600Y44000D01*
Y56600D01*
X1552700Y57500D01*
X1549500D01*
X1548200Y56200D01*
Y54300D01*
X1548100Y54200D01*
Y43700D01*
X1548700Y43100D01*
X1548800D01*
Y42178D01*
X1548737Y42065D01*
G03X1550333Y38681I2011J-1120D01*
G02X1550347Y37700I-91J-492D01*
G03X1549657Y37460I402J-2267D01*
G01X1549545Y37400D01*
X1548800D01*
Y36666D01*
X1548737Y36553D01*
G03Y34313I2011J-1120D01*
G01X1548800Y34200D01*
Y31155D01*
X1548737Y31042D01*
G03Y28802I2011J-1120D01*
G01X1548800Y28689D01*
Y25643D01*
X1548737Y25530D01*
G03X1548446Y24446I2011J-1121D01*
G02X1547446Y23462I-1000J16D01*
G01X1546158D01*
G02X1545164Y24565I0J1000D01*
G03X1545171Y24948I-2290J233D01*
G03X1544999Y25687I-2297J-145D01*
G01X1544964Y25769D01*
X1544900Y25902D01*
Y29216D01*
X1544967Y29358D01*
X1544989Y29409D01*
G03Y31221I-2115J906D01*
G01X1544967Y31272D01*
X1544900Y31414D01*
Y32834D01*
G02X1544635Y34344I500J866D01*
G03X1544973Y36773I-1761J1483D01*
G01X1545600Y37400D01*
Y49400D01*
X1544381Y50619D01*
G03X1540973Y51064I-1506J1742D01*
G02X1541102Y50202I-826J-564D01*
G01X1540600Y49700D01*
X1540500D01*
X1540000Y49200D01*
Y37500D01*
X1540761Y36739D01*
G03X1541113Y34344I2113J-913D01*
G02X1540800Y32808I-765J-644D01*
G01Y31321D01*
X1540759Y31226D01*
G03Y29404I2115J-911D01*
G01X1540800Y29309D01*
Y25810D01*
X1540759Y25715D01*
G03X1540617Y24348I2115J-911D01*
G03X1540678Y24112I2256J457D01*
G01X1540701Y24039D01*
Y23962D01*
G02X1540201Y23462I-500J0D01*
G01X1539836D01*
X1537074Y20700D01*
X1536438D01*
X1536308Y20792D01*
G03X1536252Y20830I-1320J-1886D01*
G02X1536268Y22489I567J824D01*
G03X1536536Y26126I-1268J1922D01*
G01X1536461Y26194D01*
X1536268Y26601D01*
X1536362Y26936D01*
G02X1536843Y27300I481J-136D01*
G01X1537100D01*
Y28974D01*
X1537136Y29064D01*
G03Y30780I-2136J858D01*
G01X1537100Y30870D01*
Y34485D01*
X1537136Y34575D01*
G03Y36291I-2136J858D01*
G01X1537100Y36381D01*
Y37400D01*
X1536203D01*
X1536091Y37460D01*
G03X1535401Y37700I-1092J-2027D01*
G02X1535415Y38681I105J489D01*
G03X1536832Y42339I-415J2264D01*
G01X1536750Y42446D01*
X1536717Y42713D01*
X1536937Y43233D01*
X1537200Y43408D01*
Y45776D01*
X1537224Y45864D01*
X1537233Y45900D01*
G03Y47014I-2233J557D01*
G01X1537224Y47050D01*
X1537200Y47138D01*
Y51288D01*
X1537224Y51376D01*
X1537233Y51412D01*
G03Y52526I-2233J557D01*
G01X1537224Y52562D01*
X1537200Y52650D01*
Y54200D01*
X1536973D01*
G02X1536473Y54700I0J500D01*
G01Y54850D01*
X1536555Y54975D01*
G03X1533842Y55440I-1255J825D01*
G02X1532871Y54200I-971J-240D01*
G01X1532800D01*
Y52650D01*
X1532776Y52562D01*
X1532767Y52526D01*
G03Y51412I2233J-557D01*
G01X1532776Y51376D01*
X1532800Y51288D01*
Y47138D01*
X1532776Y47050D01*
X1532767Y47014D01*
G03Y45900I2233J-557D01*
G01X1532776Y45864D01*
X1532800Y45776D01*
Y43400D01*
X1532812D01*
X1533062Y43234D01*
X1533168Y42983D01*
Y42347D01*
X1533084Y42221D01*
G03X1534585Y38681I1916J-1276D01*
G02X1534599Y37700I-91J-492D01*
G03X1533909Y37460I402J-2267D01*
G01X1533797Y37400D01*
X1532900D01*
Y36381D01*
X1532864Y36291D01*
G03Y34575I2136J-858D01*
G01X1532900Y34485D01*
Y30870D01*
X1532864Y30780D01*
G03Y29064I2136J-858D01*
G01X1532900Y28974D01*
Y27300D01*
X1533157D01*
G02X1533638Y26936I0J-500D01*
G01X1533732Y26601D01*
X1533539Y26194D01*
X1533464Y26126D01*
G03X1533732Y22489I1536J-1715D01*
G02X1533748Y20830I-551J-835D01*
G03Y16966I1252J-1932D01*
G02Y15318I-567J-824D01*
G03Y11454I1252J-1932D01*
G02X1533732Y9795I-567J-824D01*
G03X1533249Y9367I1270J-1920D01*
G01X1533236Y9351D01*
X1533232Y9347D01*
X1533218Y9330D01*
X1533204Y9314D01*
X1533187Y9293D01*
X1533119Y9207D01*
X1532718Y9000D01*
X1530100D01*
G02X1529600Y9500I0J500D01*
G01Y16427D01*
G02X1529013Y17973I232J973D01*
G03X1527696Y21523I-1887J1319D01*
G01X1527539Y21563D01*
X1527402Y21726D01*
G02Y22367I384J320D01*
G01X1527539Y22532D01*
X1527697Y22572D01*
G03X1527727Y22580I-578J2229D01*
G01X1527795Y22600D01*
X1529300D01*
Y24041D01*
X1529323Y24114D01*
G03Y25492I-2197J689D01*
G01X1529300Y25565D01*
Y29553D01*
X1529323Y29626D01*
G03Y31004I-2197J689D01*
G01X1529300Y31077D01*
Y32898D01*
G02X1528943Y34414I432J902D01*
G03X1528909Y37284I-1817J1414D01*
G02X1528859Y37359I389J314D01*
G01X1529800Y38300D01*
X1529799Y49300D01*
Y49400D01*
Y51999D01*
X1529800Y52000D01*
Y52200D01*
X1529798Y52202D01*
X1529800D01*
Y53200D01*
X1528400Y54600D01*
X1527672D01*
G03X1526574I-549J-2237D01*
G01X1525000D01*
X1524500Y54100D01*
X1524502Y49400D01*
X1524500D01*
Y35300D01*
X1525144Y34656D01*
G03X1525309Y34414I1981J1173D01*
G02X1524800Y32840I-789J-614D01*
G01Y22600D01*
X1526457D01*
X1526525Y22580D01*
G03X1526555Y22572I608J2221D01*
G01X1526713Y22532D01*
X1526850Y22369D01*
G02Y21728I-384J-320D01*
G01X1526713Y21563D01*
X1526556Y21523D01*
G03X1525239Y17973I570J-2231D01*
G02X1524900Y16523I-819J-573D01*
G01Y14372D01*
X1524886Y14314D01*
G03Y13246I2240J-534D01*
G01X1524900Y13188D01*
Y9500D01*
G02X1524400Y9000I-500J0D01*
G01X1522000D01*
G02X1521500Y9500I0J500D01*
G01Y12886D01*
X1521510Y12935D01*
G03Y13837I-2258J451D01*
G01X1521500Y13886D01*
Y18398D01*
X1521510Y18447D01*
G03Y19349I-2258J451D01*
G01X1521500Y19398D01*
Y21100D01*
X1519927D01*
X1519863Y21118D01*
G03X1519718Y21152I-598J-2223D01*
G03X1519653Y21165I-484J-2250D01*
G02X1519667Y22146I105J489D01*
G03X1521069Y25822I-415J2264D01*
G01X1521041Y25858D01*
X1520988Y25925D01*
X1520849Y26296D01*
X1520995Y26679D01*
G02X1521462Y27000I467J-179D01*
G01X1521500D01*
Y29422D01*
X1521510Y29471D01*
G03Y30373I-2258J451D01*
G01X1521500Y30422D01*
Y34933D01*
X1521510Y34982D01*
G03Y35884I-2258J451D01*
G01X1521500Y35933D01*
Y37961D01*
G02X1521059Y39519I344J939D01*
G03X1521196Y42177I-1807J1426D01*
G01X1521182Y42199D01*
X1521145Y42257D01*
X1521037Y42602D01*
X1521352Y43300D01*
X1521400D01*
Y45630D01*
X1521427Y45709D01*
G03Y47205I-2175J748D01*
G01X1521400Y47284D01*
Y51142D01*
X1521427Y51221D01*
G03Y52717I-2175J748D01*
G01X1521400Y52796D01*
Y54400D01*
X1520694D01*
G02X1519697Y55480I0J1000D01*
G03X1516812Y55028I-1497J121D01*
G01X1516831Y54982D01*
X1516900Y54839D01*
Y43300D01*
X1516977D01*
X1517224Y43141D01*
X1517403Y42745D01*
G02X1517358Y42254I-456J-206D01*
G03X1517445Y39519I1894J-1309D01*
G02X1516700Y37901I-785J-619D01*
G01Y26940D01*
G02X1517234Y25518I-342J-940D01*
G03X1518837Y22146I2018J-1108D01*
G02X1518851Y21165I-91J-492D01*
G03X1518786Y21152I419J-2263D01*
G03X1518641Y21118I453J-2257D01*
G01X1518577Y21100D01*
X1516900D01*
Y9500D01*
G02X1516400Y9000I-500J0D01*
G01X1489600D01*
X1489066Y9534D01*
G02X1489144Y11018I707J707D01*
G03X1486701Y29856I-7018J8667D01*
G02Y31679I410J912D01*
G03X1485355Y52524I-4575J10171D01*
G02X1485000Y53003I145J479D01*
G01Y56147D01*
X1485202Y56414D01*
X1485364Y56460D01*
G03Y79366I-3238J11453D01*
G01X1485363D01*
G02X1485000Y79847I137J481D01*
G01Y87111D01*
X1485674Y87785D01*
X1489302Y91412D01*
Y111870D01*
X1493645Y116213D01*
G03X1493598Y118948I-1345J1345D01*
G02X1493574Y120385I683J730D01*
G01X1493944Y120755D01*
Y126358D01*
G03X1490140I-1902J0D01*
G01Y122331D01*
X1482126Y114316D01*
X1480958Y113149D01*
G02X1480251I-353J354D01*
G01X1477000Y116400D01*
X1407161D01*
G02X1406250Y117811I0J1000D01*
G03X1399907Y120996I-3238J1460D01*
G02X1398325Y120775I-874J486D01*
G01X1390000Y129100D01*
Y134642D01*
X1390244Y135070D01*
X1390352Y135137D01*
G03Y146195I-3422J5529D01*
G01X1390244Y146262D01*
X1390000Y146690D01*
Y151800D01*
X1377800Y164000D01*
X1339000D01*
X1332567Y157567D01*
G02X1331071Y157659I-707J707D01*
G03X1321945Y148533I-5125J-4001D01*
G02X1322037Y147037I-615J-789D01*
G01X1314807Y139807D01*
G02X1313161Y140172I-707J708D01*
G03X1306409Y137976I-3338J-1215D01*
G02X1305448Y136700I-961J-276D01*
G01X1221400D01*
X1214250Y129550D01*
Y104950D01*
X1215235Y103965D01*
X1215268Y103604D01*
X1215165Y103455D01*
G03X1216007Y101150I1235J-855D01*
G02X1216647Y99751I-261J-965D01*
G03X1219318Y99820I1353J-651D01*
G02X1220195Y101300I877J480D01*
G01X1221062D01*
G02X1221917Y99780I1J-1000D01*
G03X1224483I1283J-780D01*
G02X1225338Y101300I854J520D01*
G01X1232067D01*
X1244370Y88997D01*
Y31397D01*
X1245350Y30417D01*
Y12450D01*
X1239900Y7000D01*
X691834D01*
G02X690835Y8058I0J1000D01*
G03X689795Y10200I-2292J211D01*
G02Y11848I567J824D01*
G03Y15712I-1252J1932D01*
G02X689811Y17371I567J824D01*
G03X690824Y19603I-1268J1921D01*
G02X691815Y20738I991J135D01*
G01X695336D01*
X697720Y18355D01*
X699684Y16391D01*
X699722Y16303D01*
G03X701697Y18278I1378J597D01*
G01X701609Y18316D01*
X699285Y20641D01*
X696464Y23462D01*
X691827D01*
G02X690833Y24565I0J1000D01*
G03X690644Y25744I-2290J238D01*
G01X690600Y25842D01*
Y29276D01*
X690644Y29374D01*
G03Y31256I-2101J941D01*
G01X690600Y31354D01*
Y32900D01*
X690020D01*
G02X689587Y33650I0J500D01*
G01X689690Y33828D01*
X689791Y33893D01*
G03X689769Y37776I-1248J1934D01*
G01X689659Y37845D01*
X689535Y38070D01*
Y38200D01*
G02X690035Y38700I500J0D01*
G01X690700D01*
Y40530D01*
X690726Y40608D01*
G03Y42070I-2183J731D01*
G01X690700Y42148D01*
Y46042D01*
X690726Y46120D01*
G03Y47582I-2183J731D01*
G01X690700Y47660D01*
Y49700D01*
X690676D01*
G02X690205Y50032I0J500D01*
G01X690070Y50411D01*
X690127Y50686D01*
X690223Y50789D01*
G03X686863I-1680J1573D01*
G01X686959Y50686D01*
X687016Y50411D01*
X686881Y50032D01*
G02X686410Y49700I-471J168D01*
G01X686200D01*
Y38626D01*
G02X686647Y37133I-377J-926D01*
G03X687393Y33833I1896J-1306D01*
G01X687510Y33766D01*
X687643Y33535D01*
Y33400D01*
G02X687143Y32900I-500J0D01*
G01X686400D01*
Y31160D01*
X686361Y31048D01*
X686355Y31029D01*
X686353Y31023D01*
G03Y29607I2190J-708D01*
G01X686355Y29601D01*
X686361Y29582D01*
X686400Y29470D01*
Y25648D01*
X686361Y25536D01*
X686354Y25513D01*
X686352Y25507D01*
G03X686328Y24176I2191J-705D01*
G01X686338Y24143D01*
X686370Y24038D01*
Y23962D01*
G02X685870Y23462I-500J0D01*
G01X685536D01*
X685026Y22952D01*
X683939D01*
G02X682949Y24090I0J1000D01*
G03X682581Y25693I-2280J320D01*
G01X682541Y25752D01*
X682430Y26100D01*
X682673Y26652D01*
X682900Y26800D01*
Y29350D01*
X682913Y29406D01*
G03Y30438I-2244J516D01*
G01X682900Y30494D01*
Y34861D01*
X682913Y34917D01*
G03Y35949I-2244J516D01*
G01X682900Y36005D01*
Y38101D01*
G02X682529Y39589I437J899D01*
G03X682524Y42308I-1860J1356D01*
G02X682900Y43803I806J592D01*
G01Y45885D01*
X682913Y45941D01*
G03Y46973I-2244J516D01*
G01X682900Y47029D01*
Y51397D01*
X682913Y51453D01*
G03Y52485I-2244J516D01*
G01X682900Y52541D01*
Y54739D01*
X682968Y54881D01*
X682988Y54928D01*
G03X680098Y55500I-1388J572D01*
G02X679098Y54500I-1000J0D01*
G01X678500D01*
Y52747D01*
X678476Y52672D01*
G03Y51266I2193J-703D01*
G01X678500Y51191D01*
Y47235D01*
X678476Y47160D01*
G03Y45754I2193J-703D01*
G01X678500Y45679D01*
Y43771D01*
G02X678814Y42308I-492J-871D01*
G03X679543Y38936I1855J-1364D01*
G01X679661Y38870D01*
X679798Y38636D01*
Y38500D01*
G02X679298Y38000I-500J0D01*
G01X678600D01*
Y36448D01*
X678558Y36352D01*
G03Y34514I2111J-919D01*
G01X678600Y34418D01*
Y30937D01*
X678558Y30841D01*
G03Y29003I2111J-919D01*
G01X678600Y28907D01*
Y26800D01*
X678796Y26358D01*
Y25757D01*
X678719Y25635D01*
G03X678367Y24376I1950J-1224D01*
G02X677367Y23362I-1000J-14D01*
G01X675800D01*
G02X675300Y23862I0J500D01*
G01Y33149D01*
G02X674757Y34623I309J951D01*
G03X674615Y37235I-1962J1203D01*
G01X674533Y37341D01*
X674497Y37607D01*
X674700Y38097D01*
Y40039D01*
X674771Y40158D01*
G03Y42520I-1976J1181D01*
G01X674700Y42639D01*
Y45551D01*
X674771Y45670D01*
G03Y48032I-1976J1181D01*
G01X674700Y48151D01*
Y49400D01*
X674133D01*
G02X673633Y49900I0J500D01*
G01Y50038D01*
X673773Y50273D01*
X673894Y50339D01*
G03X670943Y50994I-1099J2023D01*
G02X670600Y49513I-804J-594D01*
G01Y47548D01*
X670581Y47481D01*
G03Y46221I2214J-630D01*
G01X670600Y46154D01*
Y42036D01*
X670581Y41969D01*
G03Y40709I2214J-630D01*
G01X670600Y40642D01*
Y38300D01*
X670623D01*
X670875Y38132D01*
X671097Y37596D01*
X670975Y37240D01*
X670931Y37179D01*
G03X670833Y34623I1864J-1351D01*
G02X670400Y33192I-852J-523D01*
G01Y23862D01*
G02X669900Y23362I-500J0D01*
G01X668223D01*
G02X667223Y24376I0J1000D01*
G03X666855Y25658I-2302J33D01*
G02X667200Y27068I841J542D01*
G01Y29596D01*
X667205Y29634D01*
X667206Y29641D01*
Y29647D01*
X667209Y29674D01*
G03X667208Y30183I-2288J250D01*
G01X667204Y30214D01*
X667200Y30248D01*
Y35107D01*
X667205Y35145D01*
X667206Y35152D01*
Y35158D01*
X667209Y35185D01*
G03X667208Y35694I-2288J250D01*
G01X667204Y35725D01*
X667200Y35759D01*
Y38079D01*
G02X666781Y39589I389J921D01*
G03X666776Y42308I-1860J1356D01*
G02X667500Y43897I806J592D01*
G01Y54200D01*
G02X666542Y55480I2J1000D01*
G03X663658I-1442J420D01*
G02X662700Y54200I-960J-280D01*
G01Y52577D01*
X662684Y52508D01*
X662674Y52465D01*
G03Y51473I2247J-496D01*
G01X662684Y51430D01*
X662700Y51361D01*
Y47065D01*
X662684Y46996D01*
X662674Y46953D01*
G03Y45961I2247J-496D01*
G01X662684Y45918D01*
X662700Y45849D01*
Y43798D01*
G02X663066Y42308I-440J-898D01*
G03X663061Y39589I1855J-1363D01*
G02X662700Y38106I-808J-589D01*
G01Y36041D01*
X662684Y35972D01*
X662674Y35929D01*
G03Y34937I2247J-496D01*
G01X662684Y34894D01*
X662700Y34825D01*
Y30530D01*
X662684Y30461D01*
X662674Y30418D01*
G03Y29426I2247J-496D01*
G01X662684Y29383D01*
X662700Y29314D01*
Y27200D01*
X662940D01*
G02X663417Y26851I0J-500D01*
G01X663492Y26613D01*
G02X663368Y26110I-477J-149D01*
G01X663229Y25971D01*
G03X663653Y22489I1692J-1561D01*
G02X663669Y20830I-551J-835D01*
G03X662675Y19401I1252J-1931D01*
G03X663486Y17098I2246J-503D01*
G01X663508Y17080D01*
X663700Y16888D01*
Y15396D01*
X663508Y15204D01*
X663486Y15186D01*
G03Y11586I1435J-1800D01*
G01X663508Y11568D01*
X663700Y11376D01*
Y10000D01*
X660700Y7000D01*
X660200D01*
G02X659700Y7500I0J500D01*
G01Y16617D01*
G02X659024Y18112I183J983D01*
G03X658771Y20818I-1977J1180D01*
G01X658678Y20923D01*
X658628Y21196D01*
X658677Y21326D01*
X658771Y21576D01*
G02X659239Y21900I468J-176D01*
G01X659400D01*
Y33213D01*
G02X659009Y34623I461J887D01*
G03X658911Y37179I-1962J1205D01*
G01X658867Y37240D01*
X658745Y37596D01*
X658974Y38150D01*
X659200Y38300D01*
Y40516D01*
X659227Y40595D01*
G03Y42083I-2180J744D01*
G01X659200Y42162D01*
Y46028D01*
X659227Y46107D01*
G03Y47595I-2180J744D01*
G01X659200Y47674D01*
Y49600D01*
X659064D01*
G02X658588Y49945I-1J500D01*
G01X658466Y50321D01*
X658536Y50600D01*
X658640Y50700D01*
G03X655100Y51134I-1593J1662D01*
G02X654700Y49705I-846J-534D01*
G01Y38400D01*
X654750D01*
X655117Y38155D01*
X655349Y37597D01*
X655227Y37240D01*
X655183Y37179D01*
G03X655085Y34623I1864J-1351D01*
G02X654500Y33136I-852J-523D01*
G01Y21841D01*
G02X655036Y20413I-337J-941D01*
G03X655070Y18112I2011J-1121D01*
G02X654400Y16618I-859J-512D01*
G01Y7500D01*
G02X653900Y7000I-500J0D01*
G01X652473D01*
G02X651473Y7962I-1J1000D01*
G03X651177Y9008I-2301J-86D01*
G02X651700Y10438I870J492D01*
G01Y21404D01*
G02X650999Y23009I92J996D01*
G03X651107Y25658I-1826J1401D01*
G02X651700Y27169I841J542D01*
G01Y38010D01*
G02X651033Y39589I141J990D01*
G03X651165Y42099I-1860J1356D01*
G02X651600Y43503I865J501D01*
G01Y54700D01*
X650800D01*
G02X649801Y55660I0J1000D01*
G03X646815Y55374I-1501J-61D01*
G01X646819Y55351D01*
X646826Y55309D01*
X646838Y55250D01*
Y54992D01*
X646546Y54700D01*
X646500D01*
Y43583D01*
G02X647181Y42099I-184J-983D01*
G03X647313Y39589I1992J-1154D01*
G02X646700Y38019I-808J-589D01*
G01Y27153D01*
G02X647239Y25658I-302J-953D01*
G03X647347Y23009I1934J-1248D01*
G02X646600Y21401I-793J-609D01*
G01Y10454D01*
G02X647169Y9008I-301J-953D01*
G03X646873Y7962I2005J-1132D01*
G02X645873Y7000I-999J38D01*
G01X625800D01*
X620636Y12164D01*
X620616Y12546D01*
X620736Y12695D01*
G03X617572Y29372I-8689J6990D01*
G01X617456Y29438D01*
X617200Y29874D01*
Y31661D01*
X617456Y32097D01*
X617572Y32163D01*
G03Y51537I-5525J9687D01*
G01X617456Y51603D01*
X617200Y52039D01*
Y56874D01*
G02X617472Y57319I500J0D01*
G03Y78507I-5425J10594D01*
G02X617200Y78952I228J445D01*
G01Y85098D01*
X619902Y87800D01*
Y106712D01*
X624003Y110813D01*
G03X623956Y113548I-1345J1345D01*
G02X623932Y114985I683J730D01*
G01X624102Y115155D01*
Y120258D01*
G03X620298I-1902J0D01*
G01Y116731D01*
X615183Y111615D01*
X614437Y110870D01*
G02X613730I-354J354D01*
G01X605200Y119400D01*
X600700D01*
X600200Y118900D01*
X536780D01*
X536490Y119181D01*
X536484Y119384D01*
G03X530465Y121826I-3550J-112D01*
G02X529063Y121837I-695J718D01*
G01X521900Y129000D01*
Y136569D01*
G03Y144763I-5049J4097D01*
G01Y153000D01*
X514400Y160500D01*
X508793D01*
G02X508440Y160647I1J500D01*
G01X507785Y161302D01*
X470452D01*
X469650Y160500D01*
X469300D01*
X463793Y154993D01*
G02X462124Y155428I-707J707D01*
G03X454097Y147401I-6257J-1770D01*
G02X454532Y145732I-272J-962D01*
G01X444550Y135750D01*
X443725D01*
G02X442851Y137235I0J1000D01*
G03X436637I-3107J1722D01*
G02X435763Y135750I-874J-485D01*
G01X365650D01*
X360000Y130100D01*
Y124044D01*
G02X359500Y123544I-500J0D01*
G01X350700D01*
G03X349121Y122703I0J-1903D01*
G01X349055Y122605D01*
X348828Y122476D01*
G02X348229Y122559I-245J436D01*
G01X347802Y122986D01*
Y125100D01*
G03X343998I-1902J0D01*
G01Y121410D01*
X348668Y116740D01*
X356422D01*
X356707Y116455D01*
G02X356816Y115909I-353J-354D01*
G01X356739Y115725D01*
X356682Y115661D01*
X356681Y115660D01*
G03X358862Y113594I1118J-1003D01*
G02X359569I354J-354D01*
G01X360000Y113163D01*
Y110600D01*
X373598Y97002D01*
Y37069D01*
X380281Y30387D01*
X381260Y29408D01*
G02X381400Y29061I-360J-347D01*
G01Y12000D01*
X377800Y8400D01*
X370343D01*
G02X369569Y10034I-1J1000D01*
G03X365235I-2167J1776D01*
G02X364461Y8400I-773J-634D01*
G01X362469D01*
G02X361695Y10034I-1J1000D01*
G03X357361I-2167J1776D01*
G02X356587Y8400I-773J-634D01*
G01X346721D01*
G02X345947Y10034I-1J1000D01*
G03X341613I-2167J1776D01*
G02X340839Y8400I-773J-634D01*
G01X338847D01*
G02X338073Y10034I-1J1000D01*
G03X333739I-2167J1776D01*
G02X332965Y8400I-773J-634D01*
G01X313244D01*
G02X312712Y10246I1J1000D01*
G03X311347Y29856I-5940J9439D01*
G02Y31679I410J912D01*
G03X302197I-4575J10171D01*
G02Y29856I-410J-911D01*
G03X300832Y10246I4575J-10171D01*
G02X300300Y8400I-533J-846D01*
G01X38600D01*
X35500Y11500D01*
Y28100D01*
X27800Y35800D01*
X8100D01*
X5800Y38100D01*
Y75936D01*
G02X7276Y76815I1000J0D01*
G03Y83501I1812J3343D01*
G02X5800Y84380I-476J879D01*
G01Y87736D01*
G02X7276Y88615I1000J0D01*
G03X9438Y88172I1811J3343D01*
G03X11604Y89108I-351J3786D01*
G02X13238Y88334I634J-774D01*
G01Y84082D01*
X15485Y81835D01*
X15549Y81554D01*
X15501Y81418D01*
G03X17828Y83745I3587J-1260D01*
G01X17692Y83697D01*
X17411Y83761D01*
X15962Y85210D01*
Y87653D01*
G02X17404Y88549I1000J-1D01*
G03X22872Y91587I1684J3409D01*
G02X23370Y92038I498J-49D01*
G01X40577D01*
G02X41426Y90510I0J-1000D01*
G03X47630I3102J-1927D01*
G02X48479Y92038I849J528D01*
G01X52388D01*
G02X53237Y90511I0J-1000D01*
G03X58971Y91115I3102J-1928D01*
G01X58904Y91185D01*
X58837Y91351D01*
G02X59301Y92038I464J187D01*
G01X59364D01*
X86234Y118908D01*
X114759D01*
X114847Y118873D01*
G03Y121667I553J1397D01*
G01X114759Y121632D01*
X111071D01*
G02X110346Y123321I0J1000D01*
G01X110544Y123518D01*
X110762Y123736D01*
Y127412D01*
G02X111657Y128406I1000J0D01*
G03X112053Y128503I-156J1494D01*
G01X112142Y128538D01*
X116636D01*
X118536Y126638D01*
G02X118628Y125330I-707J-707D01*
G03X120740Y123218I1172J-940D01*
G02X122048Y123126I601J-799D01*
G01X122238Y122936D01*
Y115764D01*
X117578Y111103D01*
X113738Y107263D01*
G02X112028Y106594I-999J35D01*
G03X105837Y102361I-2741J-2636D01*
G03X106652Y101218I3450J1598D01*
G02X106665Y99791I-694J-720D01*
G01X103538Y96664D01*
Y89036D01*
X107638Y84936D01*
Y84623D01*
G02X106766Y83632I-1000J1D01*
G03Y80652I192J-1490D01*
G02X107638Y79661I-128J-992D01*
G01Y75994D01*
X109230Y74402D01*
X110542Y73091D01*
X110580Y73003D01*
G03X112555Y74978I1378J597D01*
G01X112467Y75016D01*
X111516Y75967D01*
X110362Y77122D01*
Y79970D01*
G02X111680Y80918I1000J0D01*
G03X113075Y81153I477J1424D01*
G01X113103Y81175D01*
X113174Y81232D01*
X113352Y81302D01*
G02X113885Y81189I180J-467D01*
G01X115596Y79478D01*
Y69241D01*
X115561Y69153D01*
G03X118355I1397J-553D01*
G01X118320Y69241D01*
Y80606D01*
X118109Y80817D01*
X118051Y81118D01*
X118111Y81259D01*
X118186Y81442D01*
X118250Y81510D01*
G03X116187Y83688I-1091J1032D01*
G01X116038Y83562D01*
X115648Y83578D01*
X111378Y87848D01*
G02X111492Y89360I707J707D01*
G03X109373Y96259I-2204J3098D01*
G02X108673Y97948I25J1000D01*
G01X109576Y98851D01*
X110650Y99924D01*
Y100246D01*
X110932Y100528D01*
X111004Y100564D01*
G03X111917Y101211I-1718J3392D01*
G03X112028Y101322I-2632J2744D01*
G02X113738Y100618I710J-704D01*
G01Y96082D01*
X115685Y94135D01*
X115749Y93854D01*
X115701Y93718D01*
G03X118028Y96045I3587J-1260D01*
G01X117892Y95997D01*
X117611Y96061D01*
X116462Y97210D01*
Y99517D01*
G02X117823Y100450I1000J0D01*
G03X119379Y100157I1466J3508D01*
G03X122682Y102242I-90J3801D01*
G01X122718Y102314D01*
X123000Y102596D01*
X125711D01*
G02X126707Y101511I0J-1000D01*
G03X130020Y103664I2493J-211D01*
G02X129641Y105315I328J944D01*
G01X130259Y105934D01*
X133009Y108684D01*
X133097Y108722D01*
G03X131122Y110697I-597J1378D01*
G01X131084Y110609D01*
X128694Y108220D01*
X125794Y105320D01*
X123000D01*
X122718Y105602D01*
X122682Y105674D01*
G03X120918Y107393I-3393J-1717D01*
G03X120131Y107665I-1628J-3436D01*
G02X119668Y109342I244J970D01*
G01X124962Y114636D01*
Y124064D01*
X124958Y124068D01*
G02X124956Y124774I353J354D01*
G01X125081Y124900D01*
G03X126206Y127295I-81J1500D01*
G03X123679Y127115I-1206J-895D01*
G02X122110Y126916I-862J508D01*
G01X120802Y128223D01*
X119707Y129318D01*
G02X120129Y130961I725J690D01*
G03X121106Y131872I-429J1439D01*
G03X119147Y133797I-1406J528D01*
G01X119059Y133762D01*
X116798D01*
G02X115800Y134817I0J1000D01*
G03X112800I-1500J83D01*
G02X111802Y133762I-998J-55D01*
G01X110536D01*
X108038Y131264D01*
Y127587D01*
G02X107190Y126599I-1000J0D01*
G03X106740Y126464I201J-1489D01*
G03X105895Y124961I650J-1354D01*
G02X104900Y123862I-995J-99D01*
G01X84236D01*
X61477Y101103D01*
G02X59818Y101506I-707J707D01*
G03X53328Y98327I-3479J-1113D01*
G02X52504Y96762I-825J-565D01*
G01X48364D01*
G02X47539Y98328I0J1000D01*
G03X41517I-3011J2066D01*
G02X40692Y96762I-825J-566D01*
G01X23864D01*
X22964Y97662D01*
X16336D01*
X13238Y94564D01*
Y94236D01*
G02X12738Y93736I-500J0D01*
G02X12314Y93971I0J500D01*
G03X7276Y95301I-3226J-2013D01*
G02X5800Y96180I-476J879D01*
G01Y127781D01*
G02X7537Y128457I1000J0D01*
G03X8219Y127764I10180J9337D01*
G02X8595Y127272I-1329J-1406D01*
G02X8824Y126359I-1706J-913D01*
G01Y114173D01*
G03X26608I8892J0D01*
G01Y126359D01*
G02X26837Y127272I1935J0D01*
G02X27213Y127764I1705J-914D01*
G03X29323Y130305I-9496J10032D01*
G03X7531Y147127I-11607J7490D01*
G02X5800Y147809I-731J682D01*
G01Y154900D01*
X15100Y164200D01*
X43900D01*
X49088Y169388D01*
G02X50767Y168915I707J-707D01*
G03X53613Y167032I2433J585D01*
G02X54755Y165833I165J-986D01*
G03X56787Y167768I2445J-533D01*
G02X55645Y168967I-165J986D01*
G03X53785Y171933I-2445J533D01*
G02X53312Y173612I234J972D01*
G01X54300Y174600D01*
X188600D01*
X189554Y173646D01*
G02X189290Y172043I-707J-707D01*
G03X192643Y168690I1110J-2243D01*
G02X194246Y168954I896J-443D01*
G01X204900Y158300D01*
X210558D01*
G02X211398Y156757I0J-1000D01*
G03X215602I2102J-1357D01*
G02X216442Y158300I840J543D01*
G01X223800D01*
X228850Y163350D01*
Y193050D01*
X234600Y198800D01*
X304066D01*
G02X304776Y197096I0J-1000D01*
G03X300937Y183192I9437J-10088D01*
G03X304716Y176977I13276J3816D01*
G02X305320Y175572I-1330J-1404D01*
G01Y163386D01*
G03X323106I8893J0D01*
G01Y175572D01*
G02X323710Y176977I1934J1D01*
G03X327489Y183192I-9497J10031D01*
G03X323650Y197096I-13276J3816D01*
G02X324360Y198800I710J704D01*
G01X370400D01*
X381900Y187300D01*
X448300D01*
X449724Y188724D01*
X450181D01*
X450277Y188682D01*
G03X459318Y193767I2598J5960D01*
G02X459813Y194200I495J-67D01*
G01X512905D01*
G02X513400Y193767I0J-500D01*
G03X522303Y188625I6442J876D01*
G01X522394Y188662D01*
X522838D01*
X523700Y187800D01*
X593600D01*
X595600Y189800D01*
X804700D01*
X804800Y189700D01*
X813200Y198100D01*
X815180D01*
G02X815912Y196419I0J-1000D01*
G03X816527Y176977I10112J-9411D01*
G02X816903Y176485I-1329J-1406D01*
G02X817132Y175572I-1706J-913D01*
G01Y169479D01*
X817131Y163386D01*
G03X826024Y154493I8893J0D01*
G03X834916Y163386I0J8892D01*
G01Y175572D01*
G02X835145Y176485I1935J0D01*
G02X835521Y176977I1705J-914D01*
G03X836136Y196419I-9497J10031D01*
G02X836868Y198100I732J681D01*
G01X1173448D01*
G02X1174180Y196419I0J-1000D01*
G03X1174795Y176977I10112J-9411D01*
G02X1175171Y176485I-1329J-1406D01*
G02X1175400Y175572I-1706J-913D01*
G01Y163386D01*
G03X1193184I8892J0D01*
G01Y175572D01*
G02X1193413Y176485I1935J0D01*
G02X1193789Y176977I1705J-914D01*
G03X1194404Y196419I-9497J10031D01*
G02X1195136Y198100I732J681D01*
G01X1233600D01*
X1242400Y189300D01*
X1315600D01*
X1316652Y190352D01*
G02X1318105Y190311I707J-707D01*
G03X1328811Y197466I4849J4331D01*
G02X1329712Y198900I901J434D01*
G01X1383164D01*
G02X1384065Y197466I0J-1000D01*
G03X1394822Y190368I5857J-2824D01*
G02X1396282Y190418I753J-658D01*
G01X1397400Y189300D01*
X1463600D01*
X1472700Y198400D01*
X1492400D01*
X1501500Y189300D01*
X1657900D01*
X1667000Y180200D01*
Y175830D01*
G02X1665736Y174865I-1000J0D01*
G03Y160489I-1964J-7188D01*
G02X1667000Y159524I264J-965D01*
G01Y136711D01*
G02X1665319Y135979I-1000J0D01*
G03Y128509I-3476J-3735D01*
G02X1667000Y127777I681J-732D01*
G01Y116775D01*
G02X1665736Y115810I-1000J0D01*
G03Y101434I-1964J-7188D01*
G02X1667000Y100469I264J-965D01*
G01Y45500D01*
G37*
G36*
G01X412600Y13817D02*
G02X413038Y14313I500J0D01*
G03X414529Y15408I-238J1887D01*
G01X414590Y15542D01*
X414836Y15700D01*
X421200D01*
X434000Y28500D01*
Y43300D01*
X425200Y52100D01*
X421100D01*
G02X420600Y52600I0J500D01*
G01Y75920D01*
G02X421731Y76911I1000J0D01*
G03Y79889I198J1489D01*
G02X420600Y80880I-131J991D01*
G01Y94200D01*
X419494Y95306D01*
G02X419582Y96798I707J707D01*
G03X414593Y101787I-2200J2789D01*
G02X413101Y101699I-785J619D01*
G01X404500Y110300D01*
X372485D01*
X363100Y119685D01*
Y127300D01*
X366800Y131000D01*
X446152D01*
X446431Y130763D01*
X446461Y130582D01*
G03X454717Y125414I6414J1068D01*
G02X455212Y125288I141J-479D01*
G01X460098Y120402D01*
Y112715D01*
X467698Y105115D01*
Y98698D01*
X462600Y93600D01*
X460600D01*
X460200Y93200D01*
Y92600D01*
X462600Y90200D01*
Y81357D01*
G02X462433Y80984I-500J0D01*
G03Y78746I1002J-1119D01*
G02X462600Y78373I-333J-373D01*
G01Y10200D01*
X459400Y7000D01*
X419735D01*
G02X419277Y7300I0J500D01*
G03X416920Y7838I-1377J-600D01*
G02X415721Y7758I-653J758D01*
G03X415150Y7981I-820J-1258D01*
G01X414992Y8008D01*
X412600Y10400D01*
Y13817D01*
G37*
G36*
G01X519567Y89777D02*
G03X521866Y91469I872J1223D01*
G02X521987Y91979I475J157D01*
G01X527262Y97253D01*
Y99300D01*
G03X524138I-1562J0D01*
G01Y98547D01*
X522409Y96817D01*
G02X520803Y97085I-707J707D01*
G03X519400Y97962I-1403J-684D01*
G01X518253D01*
X512307Y92015D01*
G02X510600Y92723I-707J707D01*
G01Y99800D01*
X508500Y101900D01*
Y108351D01*
X512688Y112539D01*
G02X514254Y112343I707J-707D01*
G03X526083Y113840I5589J3323D01*
G01X526130Y114000D01*
X526397Y114200D01*
X598500D01*
X607400Y105300D01*
Y90389D01*
X591246Y74235D01*
Y74032D01*
G02X589954Y73075I-1000J0D01*
G03Y67045I-918J-3015D01*
G02X591246Y66088I292J-957D01*
G01Y63979D01*
G02X589939Y63027I-1000J0D01*
G03Y57407I-903J-2810D01*
G02X591246Y56455I307J-952D01*
G01Y54347D01*
G02X589954Y53390I-1000J0D01*
G03Y47360I-918J-3015D01*
G02X591246Y46403I292J-957D01*
G01Y32228D01*
X576019Y17002D01*
X560162D01*
X558080Y14920D01*
G03X560770Y12230I1345J-1345D01*
G01X561738Y13198D01*
X577595D01*
X579589Y15192D01*
G02X581026Y15168I707J-707D01*
G03X583761Y15121I1390J1298D01*
G01X596793Y28154D01*
G02X598500Y27447I707J-707D01*
G01Y8800D01*
X595600Y5900D01*
X578002D01*
G02X577042Y7180I0J1000D01*
G03X574158I-1442J420D01*
G02X573198Y5900I-960J-280D01*
G01X573173D01*
G02X572673Y6400I0J500D01*
G01Y6550D01*
X572755Y6675D01*
G03X570232Y6694I-1255J825D01*
G02X569651Y5952I-422J-268D01*
G02X568983Y7060I319J948D01*
G03X566017I-1483J240D01*
G02X565030Y5900I-987J-160D01*
G01X564935D01*
G02X564435Y6400I0J500D01*
G01Y6504D01*
X564477Y6600D01*
G03X561609Y7020I-1377J600D01*
G02X560616Y5900I-993J-120D01*
G01X514900D01*
X510600Y10200D01*
Y81992D01*
X514865Y86257D01*
G02X515539Y86288I354J-353D01*
G03X517654Y88403I961J1154D01*
G02X517685Y89077I384J320D01*
G01X518279Y89670D01*
G02X519567Y89777I707J-707D01*
G37*
G36*
G01X1305000Y8700D02*
X1302900Y10800D01*
Y30057D01*
G03Y34471I-2250J2207D01*
G01Y38100D01*
X1300600Y40400D01*
Y45200D01*
X1300200Y45600D01*
X1300100D01*
X1298100Y47600D01*
Y50200D01*
X1296500Y51800D01*
Y52900D01*
X1295300Y54100D01*
X1289700D01*
G02X1289200Y54600I0J500D01*
G01Y76730D01*
X1289357Y76975D01*
X1289490Y77037D01*
G03X1290317Y78037I-631J1363D01*
G02X1291575Y78754I971J-241D01*
G03X1292603Y78813I433J1438D01*
G02X1293862Y78399I396J-919D01*
G03X1294563Y80537I1296J759D01*
G02X1293304Y80951I-396J919D01*
G03X1290511Y80075I-1296J-759D01*
G02X1289724Y79628I-499J-38D01*
G03X1289490Y79763I-865J-1228D01*
G02X1289200Y80217I210J454D01*
G01Y88100D01*
X1273700Y103600D01*
X1239389D01*
X1234502Y108488D01*
Y122287D01*
X1233000Y123788D01*
Y126700D01*
X1236400Y130100D01*
X1316600D01*
X1316653Y130047D01*
G03X1321226Y125382I6301J1603D01*
G01X1321353Y125347D01*
X1330178Y116522D01*
Y107336D01*
X1338100Y99414D01*
Y89100D01*
X1333412Y84412D01*
X1333237Y84393D01*
G03X1331907Y83063I163J-1493D01*
G01X1331888Y82888D01*
X1331700Y82700D01*
G02X1330396Y82605I-707J707D01*
G03X1329440Y79899I-896J-1205D01*
G02X1330400Y78900I-40J-999D01*
G01Y20400D01*
X1318700Y8700D01*
X1305000D01*
G37*
G36*
G01X1446800Y23377D02*
G03X1444267Y24850I-1100J1023D01*
G02X1443790Y24500I-477J150D01*
G01X1438046D01*
X1437825Y24619D01*
X1437755Y24725D01*
G03X1435345Y22939I-1255J-826D01*
G02Y21661I-769J-639D01*
G03X1435003Y20821I1155J-960D01*
G02X1434006Y19902I-997J81D01*
G01X1432962D01*
X1428180Y15120D01*
G03X1430870Y12430I1345J-1345D01*
G01X1434538Y16098D01*
X1450995D01*
X1451526Y16629D01*
G02X1453049Y16501I707J-707D01*
G03X1455945Y16255I1552J1099D01*
G01X1468528Y28838D01*
Y37158D01*
G02X1470235Y37865I1000J0D01*
G01X1477031Y31069D01*
G02X1476801Y29484I-708J-707D01*
G03X1474307Y11733I5325J-9799D01*
G02X1474313Y10313I-701J-713D01*
G01X1470000Y6000D01*
X1448438D01*
G02X1447583Y7520I-1J1000D01*
G03X1445105Y9210I-1283J780D01*
G02X1443547Y9170I-795J606D01*
G03X1441082Y7480I-1147J-970D01*
G02X1440205Y6000I-877J-480D01*
G01X1439203D01*
G02X1438703Y6500I0J500D01*
G01Y6619D01*
X1438808Y6828D01*
X1438903Y6900D01*
G03X1436651Y7440I-903J1200D01*
G02X1435753Y6000I-898J-440D01*
G01X1435371D01*
G02X1434904Y6323I1J500D01*
G01X1434805Y6584D01*
G02X1434880Y7070I468J177D01*
G03X1432323Y7400I-1180J930D01*
G02X1431407Y6000I-916J-400D01*
G01X1380900D01*
X1378900Y8000D01*
Y75200D01*
X1376358Y77742D01*
G02Y78449I353J354D01*
G01X1384556Y86648D01*
G02X1386117Y86461I707J-707D01*
G03X1388181Y88525I1283J781D01*
G02X1387994Y90086I520J854D01*
G01X1389239Y91330D01*
G02X1389944Y91332I354J-353D01*
G03X1392451Y92789I1056J1068D01*
G02X1392580Y93272I483J130D01*
G01X1396762Y97453D01*
Y99500D01*
G03X1393638I-1562J0D01*
G01Y98747D01*
X1392909Y98017D01*
G02X1391303Y98285I-707J707D01*
G03X1389900Y99162I-1403J-684D01*
G01X1388553D01*
X1372099Y82708D01*
G02X1371392I-353J353D01*
G01X1369400Y84700D01*
Y85406D01*
G02X1369900Y85906I500J0D01*
G01X1370030D01*
X1370256Y85780D01*
X1370325Y85670D01*
G03X1370880Y87781I1275J793D01*
G02X1369400Y88658I-480J877D01*
G01Y101051D01*
X1377349Y109000D01*
X1475900D01*
X1478500Y106400D01*
Y90232D01*
X1461724Y73457D01*
Y73040D01*
G02X1460936Y72632I-500J0D01*
G03X1460337Y67155I-1822J-2572D01*
G02X1461724Y66233I387J-922D01*
G01Y63826D01*
G02X1460317Y62913I-1000J0D01*
G03Y57521I-1203J-2696D01*
G02X1461724Y56608I407J-913D01*
G01Y54202D01*
G02X1460337Y53280I-1000J0D01*
G03Y47470I-1223J-2905D01*
G02X1461724Y46548I387J-922D01*
G01Y32207D01*
X1449419Y19902D01*
X1448400D01*
G02X1447401Y20861I0J1000D01*
G03X1446880Y21938I-1501J-61D01*
G02X1446800Y23377I652J758D01*
G37*
%LPC*%
G75*
G36*
G01X1646700Y91400D02*
Y98100D01*
X1647400Y98800D01*
X1648900D01*
X1649900Y97800D01*
Y91400D01*
X1649000Y90500D01*
X1647600D01*
X1646700Y91400D01*
G37*
G36*
G01X1633200Y119700D02*
Y120900D01*
X1634300Y122000D01*
X1640500D01*
X1641500Y121000D01*
Y119700D01*
X1640500Y118700D01*
X1634200D01*
X1633200Y119700D01*
G37*
G36*
G01X1614400Y119800D02*
Y121100D01*
X1615400Y122100D01*
X1621600D01*
X1622600Y121100D01*
Y119800D01*
X1621700Y118900D01*
X1615300D01*
X1614400Y119800D01*
G37*
G36*
G01X1592900Y105000D02*
Y106400D01*
X1593800Y107300D01*
X1600100D01*
X1601200Y106200D01*
Y105000D01*
X1600200Y104000D01*
X1593900D01*
X1592900Y105000D01*
G37*
G36*
G01X1558400Y121400D02*
Y122700D01*
X1559400Y123700D01*
X1565600D01*
X1566600Y122700D01*
Y121300D01*
X1565700Y120400D01*
X1559400D01*
X1558400Y121400D01*
G37*
G36*
G01X1539500Y125300D02*
Y126500D01*
X1540600Y127600D01*
X1546700D01*
X1547700Y126600D01*
Y125200D01*
X1546800Y124300D01*
X1540500D01*
X1539500Y125300D01*
G37*
G36*
G01X1541000Y92500D02*
Y94000D01*
X1542100Y95100D01*
X1548100D01*
X1549300Y93900D01*
Y92500D01*
X1548300Y91500D01*
X1542000D01*
X1541000Y92500D01*
G37*
G36*
G01X1527700Y72200D02*
Y73400D01*
X1528800Y74500D01*
X1535100D01*
X1536200Y73400D01*
Y72400D01*
X1535000Y71200D01*
X1528700D01*
X1527700Y72200D01*
G37*
G36*
G01X776500Y91500D02*
Y97700D01*
X777500Y98700D01*
X778900D01*
X779800Y97800D01*
Y91500D01*
X778800Y90500D01*
X777500D01*
X776500Y91500D01*
G37*
G36*
G01X763200Y119500D02*
Y121100D01*
X764100Y122000D01*
X770400D01*
X771400Y121000D01*
Y119600D01*
X770400Y118600D01*
X764100D01*
X763200Y119500D01*
G37*
G36*
G01X744200Y119900D02*
Y120900D01*
X745300Y122000D01*
X751700D01*
X752500Y121200D01*
Y119700D01*
X751500Y118700D01*
X745400D01*
X744200Y119900D01*
G37*
G36*
G01X725000Y113500D02*
X723700Y114800D01*
Y115900D01*
X724183Y116383D01*
X724192Y116393D01*
G02X724316Y116516I1118J-1003D01*
G01X724700Y116900D01*
X731000D01*
X731900Y116000D01*
Y114600D01*
X730800Y113500D01*
X725000D01*
G37*
G36*
G01X700000Y91400D02*
Y97800D01*
X700900Y98700D01*
X702400D01*
X703300Y97800D01*
Y91400D01*
X702300Y90400D01*
X701000D01*
X700000Y91400D01*
G37*
G36*
G01X652700Y91500D02*
Y97800D01*
X653600Y98700D01*
X655100D01*
X656100Y97700D01*
Y91500D01*
X655100Y90500D01*
X653700D01*
X652700Y91500D01*
G37*
G36*
G01X660000Y120300D02*
Y121700D01*
X660900Y122600D01*
X667200D01*
X668200Y121600D01*
Y120300D01*
X667200Y119300D01*
X661000D01*
X660000Y120300D01*
G37*
G36*
G01X679000Y129000D02*
Y130200D01*
X680000Y131200D01*
X686300D01*
X687200Y130300D01*
Y129000D01*
X686200Y128000D01*
X680000D01*
X679000Y129000D01*
G37*
G36*
G01X1092118Y32095D02*
G02X1111112I9497J10031D01*
G03X1110508Y30690I1330J-1404D01*
G01Y18504D01*
G02X1092722I-8893J0D01*
G01Y30690D01*
G03X1092118Y32095I-1934J1D01*
G37*
G36*
G01X774164D02*
G02X793158I9497J10031D01*
G03X792554Y30690I1330J-1404D01*
G01Y18504D01*
G02X774768I-8893J0D01*
G01Y30690D01*
G03X774164Y32095I-1934J1D01*
G37*
G36*
G01X85652Y100643D02*
G03X85124Y100177I-29J-499D01*
G02X81712Y103589I-3195J217D01*
G03X82177Y104116I-34J499D01*
G02X82178Y104545I3689J206D01*
G03X81712Y105073I-499J29D01*
G02X85124Y108484I217J3195D01*
G03X85652Y108019I499J34D01*
G02X86870Y107886I214J-3688D01*
G01Y107044D01*
G03X87128Y106606I500J0D01*
G02X88120Y105632I-1261J-2276D01*
G01X88187Y105515D01*
X88418Y105382D01*
X89408D01*
G02X89560Y104331I-3542J-1049D01*
G02X89554Y104116I-3694J-4D01*
G03X90020Y103589I499J-28D01*
G02X86608Y100177I-217J-3195D01*
G03X86080Y100643I-499J-33D01*
G02X85652I-214J3688D01*
G37*
G36*
G01Y69147D02*
G03X85124Y68681I-29J-499D01*
G02X81712Y72093I-3195J217D01*
G03X82177Y72620I-34J499D01*
G02X82178Y73049I3689J206D01*
G03X81712Y73577I-499J29D01*
G02X85124Y76988I217J3195D01*
G03X85652Y76523I499J34D01*
G02X86080I214J-3688D01*
G03X86608Y76988I29J499D01*
G02X90020Y73577I3195J-216D01*
G03X89554Y73049I33J-499D01*
G02X89560Y72835I-3688J-210D01*
G02X89554Y72620I-3694J-4D01*
G03X90020Y72093I499J-28D01*
G02X86608Y68681I-217J-3195D01*
G03X86080Y69147I-499J-33D01*
G02X85652I-214J3688D01*
G37*
G36*
G01X81668Y171404D02*
G02X81545Y168138I1832J-1704D01*
G03X80032Y168196I-782J-624D01*
G02X80155Y171462I-1832J1704D01*
G03X81668Y171404I782J624D01*
G37*
G36*
G01X106948Y166369D02*
G02X104970Y166652I-1148J-969D01*
G03X105012Y168289I-553J833D01*
G02X107366Y167953I1488J2011D01*
G03X106948Y166369I346J-938D01*
G37*
G36*
G01X90770Y165916D02*
G02X88353Y166377I-1370J-616D01*
G03X88382Y167781I-697J717D01*
G02X91259Y167233I1818J1719D01*
G03X90770Y165916I423J-906D01*
G37*
G36*
G01X66281Y162808D02*
G02X63939Y162271I-680J-2408D01*
G03X63764Y163890I-664J747D01*
G02X65732Y164341I736J1310D01*
G03X66281Y162808I821J-571D01*
G37*
G36*
G01X112694Y160944D02*
G02X109820Y161457I-1794J-1744D01*
G03X110106Y163056I-431J902D01*
G02X112980Y162543I1794J1744D01*
G03X112694Y160944I431J-902D01*
G37*
G36*
G01X81167Y158811D02*
G02X78434Y160475I-2367J-811D01*
G03X79233Y161789I-147J989D01*
G02X81966Y160125I2367J811D01*
G03X81167Y158811I147J-989D01*
G37*
G36*
G01X120540Y153296D02*
G02X117760Y154419I-2140J-1296D01*
G03X118360Y155904I-255J967D01*
G02X118234Y158260I2140J1296D01*
G03X117548Y159660I-906J424D01*
G02X120366Y161040I552J2440D01*
G03X121052Y159640I906J-424D01*
G02X121140Y154781I-552J-2440D01*
G03X120540Y153296I255J-967D01*
G37*
G36*
G01X91373Y150992D02*
G02X89199Y152694I-2373J-792D01*
G03X90227Y154008I79J997D01*
G02X93994Y156878I2373J792D01*
G03X95536Y157534I557J830D01*
G02X96606Y155022I2464J-434D01*
G03X95064Y154366I-557J-830D01*
G02X92401Y152306I-2464J434D01*
G03X91373Y150992I-79J-997D01*
G37*
G36*
G01X101326Y147979D02*
G02X100603Y150821I-2326J921D01*
G03X102174Y151221I641J768D01*
G02X102897Y148379I2326J-921D01*
G03X101326Y147979I-641J-768D01*
G37*
G36*
G01X111039Y142540D02*
G02X110019Y145160I-2439J559D01*
G03X111561Y145760I567J824D01*
G02X112581Y143140I2439J-559D01*
G03X111039Y142540I-567J-824D01*
G37*
G36*
G01X125367Y81132D02*
G02X124068Y79833I191J-1490D01*
G03X122949Y80952I-992J127D01*
G02X124248Y82251I-191J1490D01*
G03X125367Y81132I992J-127D01*
G37*
G36*
G01X669500Y125300D02*
Y126600D01*
X670400Y127500D01*
X676700D01*
X677600Y126600D01*
Y125300D01*
X676700Y124400D01*
X670400D01*
X669500Y125300D01*
G37*
G36*
G01X688400Y121400D02*
Y122700D01*
X689300Y123600D01*
X695600D01*
X696500Y122700D01*
Y121400D01*
X695600Y120500D01*
X689300D01*
X688400Y121400D01*
G37*
G36*
G01X671100Y92700D02*
Y94000D01*
X672000Y94900D01*
X678300D01*
X679300Y93900D01*
Y92700D01*
X678300Y91700D01*
X672100D01*
X671100Y92700D01*
G37*
G36*
G01X657600Y72200D02*
Y73600D01*
X658600Y74600D01*
X665000D01*
X666000Y73600D01*
Y72300D01*
X665000Y71300D01*
X658500D01*
X657600Y72200D01*
G37*
G36*
G01X722800Y105000D02*
Y106300D01*
X723700Y107200D01*
X730000D01*
X731000Y106200D01*
Y104900D01*
X730100Y104000D01*
X723800D01*
X722800Y105000D01*
G37*
G36*
G01X753800Y124100D02*
Y125500D01*
X754700Y126400D01*
X761000D01*
X762000Y125400D01*
Y124100D01*
X761000Y123100D01*
X754800D01*
X753800Y124100D01*
G37*
G36*
G01X745900Y92100D02*
Y93400D01*
X746900Y94400D01*
X753200D01*
X754100Y93500D01*
Y92200D01*
X753200Y91300D01*
X746700D01*
X745900Y92100D01*
G37*
G36*
G01X755400Y72100D02*
Y73600D01*
X756300Y74500D01*
X762500D01*
X763500Y73500D01*
Y72100D01*
X762600Y71200D01*
X756300D01*
X755400Y72100D01*
G37*
G36*
G01X1522800Y91400D02*
Y97800D01*
X1523700Y98700D01*
X1525300D01*
X1526200Y97800D01*
Y91600D01*
X1525000Y90400D01*
X1523800D01*
X1522800Y91400D01*
G37*
G36*
G01X1570100D02*
Y97800D01*
X1571000Y98700D01*
X1572400D01*
X1573300Y97800D01*
Y91400D01*
X1572400Y90500D01*
X1571000D01*
X1570100Y91400D01*
G37*
G36*
G01X1531200Y119300D02*
X1530100Y120400D01*
Y121700D01*
X1531000Y122600D01*
X1537300D01*
X1538300Y121600D01*
Y120300D01*
X1537300Y119300D01*
X1531200D01*
G37*
G36*
G01X1557300Y129000D02*
X1556300Y128000D01*
X1549900D01*
X1549000Y128900D01*
Y130200D01*
X1550000Y131200D01*
X1556300D01*
X1557300Y130200D01*
Y129000D01*
G37*
G36*
G01X1593800Y114700D02*
Y116100D01*
X1594700Y117000D01*
X1601000D01*
X1602000Y116000D01*
Y114700D01*
X1601100Y113800D01*
X1594700D01*
X1593800Y114700D01*
G37*
G36*
G01X1623700Y124100D02*
Y125300D01*
X1624800Y126400D01*
X1631100D01*
X1632100Y125400D01*
Y124100D01*
X1631100Y123100D01*
X1624700D01*
X1623700Y124100D01*
G37*
G36*
G01X1615700Y92200D02*
Y93400D01*
X1616900Y94600D01*
X1623200D01*
X1624300Y93500D01*
Y92200D01*
X1623100Y91000D01*
X1616900D01*
X1615700Y92200D01*
G37*
G36*
G01X1625400Y72200D02*
Y73600D01*
X1626400Y74600D01*
X1632600D01*
X1633700Y73500D01*
Y72200D01*
X1632700Y71200D01*
X1626400D01*
X1625400Y72200D01*
G37*
G36*
G01X430493Y61456D02*
G02X434096Y57853I0J-3603D01*
G01Y55353D01*
G02X427090I-3503J0D01*
G01Y58053D01*
G02X430493Y61456I3403J0D01*
G37*
G36*
G01X447485Y38625D02*
G03X447979Y38200I494J75D01*
G01X453601D01*
X453890Y38475D01*
X453900Y38675D01*
G02X455749Y37139I1500J-75D01*
G03X454982Y36180I233J-972D01*
G02X454975Y36050I-1502J16D01*
G03X455454Y35501I497J-49D01*
G02X453915Y33775I-54J-1501D01*
G03X453421Y34200I-494J-75D01*
G01X447799D01*
X447514Y33942D01*
X447494Y33750D01*
G02X445628Y35355I-1494J150D01*
G03X446380Y36275I-247J969D01*
G02X446386Y36351I1500J-80D01*
G03X445916Y36900I-498J50D01*
G02X447485Y38625I84J1500D01*
G37*
G36*
G01X579785Y61456D02*
G02X583388Y57854I1J-3602D01*
G01Y55354D01*
G02X576382I-3503J0D01*
G01Y58054D01*
G02X579785Y61456I3402J0D01*
G37*
G36*
G01X564851Y34600D02*
X564122D01*
G03X563622Y34100I0J-500D01*
G01Y33965D01*
X563690Y33849D01*
G02X557818Y32443I-2725J-1585D01*
G03X556852Y33499I-998J56D01*
G02X555558Y34325I48J1501D01*
G01X555494Y34452D01*
X555254Y34600D01*
X549245D01*
X549005Y34452D01*
X548941Y34325D01*
G02X546099Y35082I-1342J675D01*
G01X546100Y35096D01*
Y46004D01*
X546099Y46018D01*
G02Y46182I1500J82D01*
G01X546100Y46196D01*
Y47500D01*
X547049D01*
X547126Y47525D01*
G02X548072I473J-1425D01*
G01X548149Y47500D01*
X556498D01*
X556575Y47525D01*
G02X557521I473J-1425D01*
G01X557598Y47500D01*
X558600D01*
X558826Y47274D01*
X559249D01*
X559374Y47356D01*
G02X561143Y47267I824J-1256D01*
G03X562402I629J777D01*
G02X564293I945J-1167D01*
G03X565551I629J777D01*
G02X567154Y47450I945J-1167D01*
G01X567258Y47400D01*
X575185D01*
X575289Y47450D01*
G02X576603I657J-1350D01*
G01X576707Y47400D01*
X581300D01*
Y45300D01*
G03X581800Y44800I500J0D01*
G01X583500D01*
Y34666D01*
G03X582820Y33354I259J-966D01*
G02X576716Y32443I-2957J-1090D01*
G03X575751Y33499I-998J57D01*
G02X574458Y34325I49J1501D01*
G01X574394Y34452D01*
X574154Y34600D01*
X568143D01*
X567903Y34452D01*
X567839Y34325D01*
G02X565155I-1342J675D01*
G01X565091Y34452D01*
X564851Y34600D01*
G37*
G36*
G01X566350Y21801D02*
G03X566600Y22234I-250J433D01*
G01Y22612D01*
G03X566325Y23058I-500J0D01*
G02X568377Y25000I675J1342D01*
G03X568835Y24700I458J200D01*
G01X574012D01*
G03X574458Y24975I0J500D01*
G02X576903Y23280I1342J-676D01*
G03X576943Y21881I734J-679D01*
G02X574523Y20200I-1043J-1081D01*
G03X574065Y20500I-458J-200D01*
G01X568867D01*
X568597Y20291D01*
X568554Y20125D01*
G02X566350Y21801I-1454J375D01*
G37*
G36*
G01X573845Y79807D02*
G02X573006Y77773I526J-1407D01*
G03X571747Y78293I-909J-417D01*
G02X569762Y79342I-526J1407D01*
G03X568504Y80061I-971J-239D01*
G02X566980Y80468I-432J1439D01*
G03X565721Y80628I-727J-686D01*
G02X564346Y80513I-799J1272D01*
G03X563087Y80073I-384J-923D01*
G02X561309Y79371I-1315J727D01*
G03X560050Y78732I-309J-951D01*
G02X559086Y80629I-1427J468D01*
G03X560345Y81268I309J951D01*
G02X562348Y82187I1427J-468D01*
G03X563607Y82627I384J923D01*
G02X566014Y82932I1315J-727D01*
G03X567273Y82772I727J686D01*
G02X569531Y81858I799J-1272D01*
G03X570789Y81139I971J239D01*
G02X572586Y80327I432J-1439D01*
G03X573845Y79807I909J417D01*
G37*
G36*
G01X525750Y15394D02*
G02X524115Y13678I-150J-1494D01*
G03X523540Y14097I-494J-75D01*
G02X523238Y14079I-240J1483D01*
G03X522238Y13368I-42J-999D01*
G02X520800Y15302I-1438J432D01*
G03X521300Y15802I0J500D01*
G01Y20500D01*
G03X520825Y21000I-500J1D01*
G02X522361Y22849I75J1500D01*
G03X523320Y22082I972J233D01*
G02X523524Y22065I-22J-1502D01*
G03X524098Y22570I74J494D01*
G02X525750Y21106I1502J30D01*
G01X525558Y21086D01*
X525300Y20801D01*
Y15892D01*
G03X525750Y15394I500J0D01*
G37*
G36*
G01X1300572Y61456D02*
G02X1304174Y57854I0J-3602D01*
G01Y55354D01*
G02X1297169I-3503J0D01*
G01X1297170Y58054D01*
G02X1300572Y61456I3402J0D01*
G37*
G36*
G01X1323779Y33725D02*
G03X1323279Y34200I-499J-25D01*
G01X1317778D01*
X1317493Y33942D01*
X1317473Y33750D01*
G02X1315979Y35402I-1494J150D01*
G03X1316479Y35902I0J500D01*
G01Y35939D01*
X1316474Y35976D01*
G02X1316457Y36200I1485J225D01*
G03X1315938Y36699I-500J-1D01*
G02X1317312Y38650I-59J1501D01*
G03X1317789Y38300I477J150D01*
G01X1323480D01*
X1323765Y38558D01*
X1323785Y38750D01*
G02X1325748Y37173I1494J-150D01*
G03X1325061Y36214I313J-950D01*
G02Y36186I-1502J-14D01*
G03X1325748Y35227I1000J-9D01*
G02X1323779Y33725I-469J-1427D01*
G37*
G36*
G01X1449864Y61455D02*
G02X1453466Y57853I0J-3602D01*
G01Y55353D01*
G02X1446462I-3502J0D01*
G01Y58053D01*
G02X1449864Y61455I3402J0D01*
G37*
G36*
G01X1438048Y34700D02*
G02X1435104I-1472J300D01*
G01X1435069Y34875D01*
X1434793Y35100D01*
X1433850D01*
G03X1433466Y34280I0J-500D01*
G02X1427896Y32443I-2423J-2016D01*
G03X1426939Y33499I-998J57D01*
G02X1425528Y34700I61J1501D01*
G01X1425493Y34875D01*
X1425217Y35100D01*
X1419640D01*
G03X1419150Y34700I0J-500D01*
G02X1416423Y34175I-1472J300D01*
G03X1416005Y34400I-418J-275D01*
G01X1415411D01*
G03X1414911Y33900I0J-500D01*
G01Y33782D01*
X1414964Y33676D01*
G02X1411502Y35350I-2818J-1412D01*
G01X1411677Y35386D01*
X1411900Y35661D01*
Y39100D01*
X1414900D01*
G03X1415400Y39600I0J500D01*
G01Y47400D01*
X1416917D01*
X1417021Y47450D01*
G02X1418335I657J-1350D01*
G01X1418439Y47400D01*
X1426366D01*
X1426470Y47450D01*
G02X1427784I657J-1350D01*
G01X1427888Y47400D01*
X1429516D01*
X1429620Y47450D01*
G02X1430934I657J-1350D01*
G01X1431038Y47400D01*
X1432665D01*
X1432769Y47450D01*
G02X1434083I657J-1350D01*
G01X1434187Y47400D01*
X1435815D01*
X1435919Y47450D01*
G02X1437233I657J-1350D01*
G01X1437337Y47400D01*
X1445264D01*
X1445368Y47450D01*
G02X1446682I657J-1350D01*
G01X1446786Y47400D01*
X1449900D01*
Y35697D01*
X1450149Y35415D01*
X1450337Y35391D01*
G02X1446794Y32443I-396J-3127D01*
G03X1445837Y33499I-998J57D01*
G02X1444428Y34700I63J1501D01*
G01X1444393Y34875D01*
X1444117Y35100D01*
X1438538D01*
G03X1438048Y34700I0J-500D01*
G37*
G36*
G01X1393317Y14079D02*
G03X1392317Y13368I-42J-999D01*
G02X1390895Y15302I-1438J432D01*
G03X1391400Y15802I5J500D01*
G01Y20500D01*
G03X1390920Y20999I-500J-1D01*
G02X1392440Y22849I59J1501D01*
G03X1393399Y22082I972J233D01*
G02X1393603Y22065I-22J-1502D01*
G03X1394177Y22570I74J494D01*
G02X1395770Y21101I1502J30D01*
G03X1395300Y20602I30J-499D01*
G01Y15898D01*
G03X1395770Y15399I500J0D01*
G02X1394194Y13678I-91J-1499D01*
G03X1393619Y14097I-494J-75D01*
G02X1393317Y14079I-240J1483D01*
G37*
G36*
G01X1443786Y79647D02*
G02X1443223Y77433I664J-1347D01*
G03X1441964Y77753I-817J-577D01*
G02X1439818Y78855I-664J1347D01*
G03X1438559Y79655I-987J-162D01*
G02X1436990Y80147I-408J1445D01*
G03X1435731Y80387I-773J-634D01*
G02X1434518Y80278I-729J1313D01*
G03X1433259Y79678I-321J-947D01*
G02X1431301Y78802I-1408J522D01*
G03X1430042Y78324I-367J-930D01*
G02X1429252Y80400I-1340J678D01*
G03X1430511Y80878I367J930D01*
G02X1432334Y81622I1340J-678D01*
G03X1433593Y82222I321J947D01*
G02X1436162Y82653I1408J-522D01*
G03X1437421Y82413I773J634D01*
G02X1439633Y81345I730J-1313D01*
G03X1440892Y80545I987J162D01*
G02X1442527Y79967I409J-1445D01*
G03X1443786Y79647I817J577D01*
G37*
G54D36*
X99100Y127470D03*
X121958Y70900D03*
X106958Y68500D03*
X102590Y115680D03*
X108900Y137300D03*
X128600Y114510D03*
X347350Y143750D03*
X346906Y137693D03*
X357600Y108561D03*
X356861Y102961D03*
X526612Y142000D03*
X626173Y148400D03*
X617949Y147000D03*
X1211200Y144900D03*
X1217405Y143895D03*
X1495800Y147800D03*
X1487600Y147000D03*
X426200Y78100D03*
X453900Y92300D03*
X453300Y86800D03*
X451100Y81400D03*
X452100Y97000D03*
X452000Y102200D03*
X549174Y89400D03*
X546024Y79200D03*
X552324Y78500D03*
X563800Y87700D03*
X1323000Y99239D03*
X1322500Y87800D03*
X1321500Y82600D03*
X1321400Y92800D03*
X1429400Y88500D03*
X1434200Y88100D03*
X1422403Y78400D03*
X1416103D03*
G54D34*
X51900Y162300D03*
X76900Y20200D03*
X73200Y162100D03*
X62200Y169900D03*
X70400Y170000D03*
X90200Y22400D03*
X94900Y144500D03*
X83800Y154500D03*
X93900Y162900D03*
X100700Y163400D03*
X88000Y158900D03*
X96900Y169500D03*
X102500Y29400D03*
X107200Y19300D03*
X121200Y33900D03*
X102000Y141900D03*
X119900Y143200D03*
X111800Y151800D03*
X104900Y157400D03*
X115300Y170200D03*
X123900Y41000D03*
X138700Y63500D03*
X144100Y72900D03*
X139800Y90200D03*
X131400Y91300D03*
X129200Y142400D03*
X126600Y149500D03*
X165600Y19400D03*
X168100Y48400D03*
X151500Y35800D03*
X159800Y65100D03*
X161800Y86800D03*
X158200Y102400D03*
X184100Y36600D03*
X174300Y73300D03*
X181400Y84700D03*
X194400Y20200D03*
X197800Y30900D03*
Y48000D03*
X214700Y35800D03*
X195600Y64100D03*
X206700Y72700D03*
X225800Y19600D03*
X229200Y30900D03*
X216400Y100500D03*
X254400Y19200D03*
X257800Y51200D03*
X244900Y36600D03*
X254400Y74300D03*
X251600Y100100D03*
X252200Y159400D03*
X252800Y179900D03*
X268300Y36200D03*
X283600Y69500D03*
X273300Y94900D03*
X281800Y100900D03*
X267700Y145200D03*
X280000Y159800D03*
X281000Y180700D03*
X307800Y101100D03*
X300300Y140000D03*
X350000Y161800D03*
X350200Y181100D03*
X813700Y43900D03*
X809700Y86500D03*
X839700D03*
X838300Y128100D03*
X855400Y152400D03*
X857000Y189800D03*
X869700Y86500D03*
X868300Y128100D03*
X899700Y86500D03*
X898300Y128100D03*
X885400Y152400D03*
X887000Y189800D03*
X929700Y86500D03*
X928300Y128100D03*
X915400Y152400D03*
X917000Y189800D03*
X945400Y152400D03*
X947000Y189800D03*
X959000Y18000D03*
X959700Y86500D03*
X958300Y128100D03*
X975400Y152400D03*
X989700Y86500D03*
X988300Y128100D03*
X977000Y189800D03*
X1018300Y128100D03*
X1005400Y152400D03*
X1007000Y189800D03*
X1043000Y45500D03*
X1031900Y84100D03*
X1035400Y152400D03*
X1037000Y189800D03*
X1063700Y15300D03*
X1061900Y84100D03*
X1048300Y128100D03*
X1065400Y152400D03*
X1067000Y189800D03*
X1073000Y45500D03*
X1078300Y128100D03*
X1091900Y84100D03*
X1108300Y128100D03*
X1095400Y152400D03*
X1097000Y189800D03*
X1120900Y64500D03*
X1121900Y84100D03*
X1125400Y152400D03*
X1127000Y189800D03*
X1147100Y64500D03*
X1151900Y84100D03*
X1155400Y152400D03*
X1157000Y189800D03*
G54D38*
X383642Y119272D03*
X439744Y99587D03*
X532934Y40532D03*
Y79902D03*
X545414Y99587D03*
X566674D03*
X589036D03*
X1253721Y119272D03*
X1287461Y99587D03*
X1309823D03*
X1403012Y40532D03*
Y79902D03*
X1415492Y99587D03*
X1436752D03*
X1459114D03*
G54D39*
X439744Y50375D03*
Y70060D03*
Y88564D03*
X532934Y50375D03*
Y70060D03*
Y88564D03*
X542068Y32264D03*
X589036Y88564D03*
X1309823Y50375D03*
Y70060D03*
Y88564D03*
X1403012Y50375D03*
Y70060D03*
Y88564D03*
X1459114D03*
G54D35*
X81929Y92520D03*
Y84646D03*
X89803Y92520D03*
Y84646D03*
G54D33*
X44528Y41339D03*
Y53150D03*
Y64961D03*
Y76772D03*
Y112205D03*
Y124016D03*
Y135827D03*
G54D37*
X367402Y19684D03*
Y27558D03*
X359528Y19684D03*
Y27558D03*
X367402Y43306D03*
Y51180D03*
X359528Y43306D03*
Y51180D03*
X367402Y59054D03*
X359528D03*
X1229606Y11810D03*
Y19684D03*
Y27558D03*
Y43306D03*
Y51180D03*
Y59054D03*
X1237480Y11810D03*
Y19684D03*
Y27558D03*
Y43306D03*
Y51180D03*
Y59054D03*
G54D40*
X439744Y60217D03*
X1309823D03*
G54D26*
X1647618Y132244D03*
X1572775D03*
X777539D03*
X702697D03*
G54D30*
X40827Y29528D03*
Y147638D03*
G54D27*
X1600374Y132244D03*
X1525531D03*
X730295D03*
X655453D03*
X542085Y56654D03*
X1412164Y56653D03*
G54D32*
X508859Y176650D03*
X1378938D03*
G54D31*
X463859D03*
X1333938D03*
G54D28*
X1221732Y37400D03*
G54D29*
X351654D03*
%LPD*%
G75*
G54D10*
X19088Y80158D03*
Y91958D03*
X109288Y92458D03*
X119288D03*
X109288Y103958D03*
X119288D03*
G54D20*
X639283Y108622D03*
Y167677D03*
X793693Y108622D03*
Y167677D03*
X1509362Y108622D03*
Y167677D03*
G54D11*
X56339Y41339D03*
Y53150D03*
Y64961D03*
Y76772D03*
Y112205D03*
Y124016D03*
Y135827D03*
G54D21*
X641212Y132244D03*
X791764D03*
X1511291D03*
G54D12*
X89803Y108268D03*
G54D22*
X1176851Y19685D03*
Y41850D03*
G54D13*
X123100Y49600D03*
X143300Y27300D03*
X143800Y53600D03*
X144500Y40000D03*
X133100Y71300D03*
X144200Y96300D03*
X143000Y105700D03*
X141900Y154700D03*
X134800Y164000D03*
X144700Y149200D03*
X137100Y158600D03*
X137000Y170400D03*
X127400D03*
X150300Y20200D03*
X166500Y34700D03*
X153100Y49600D03*
X148800Y85000D03*
X163500Y144900D03*
X150300Y144600D03*
X156000Y138200D03*
X156500Y144800D03*
X169900Y146800D03*
X164400Y138200D03*
X169400Y153600D03*
X155600Y157900D03*
X162100Y164300D03*
X168000Y161200D03*
X149300Y164100D03*
X163200Y151600D03*
X162000Y159400D03*
X148000Y158800D03*
X152600Y152000D03*
X155900Y170000D03*
X163800Y170100D03*
X148600D03*
X180300Y20200D03*
X183100Y49600D03*
X191700Y75400D03*
X175000Y62300D03*
X174200Y96300D03*
X190400Y136600D03*
X191200Y142400D03*
X178100Y144600D03*
X184000Y138800D03*
X173600Y138700D03*
X185800Y145400D03*
X190000Y149800D03*
X179300Y156400D03*
X187100Y155800D03*
X192100Y163500D03*
X176300Y164400D03*
X175500Y151300D03*
X173700Y158700D03*
X182600Y152000D03*
X171300Y170000D03*
X177800Y170400D03*
X210300Y20200D03*
X213100Y49600D03*
X209400Y60900D03*
X204200Y96300D03*
X196200Y102300D03*
X211300Y138600D03*
X204200Y139200D03*
X195900Y146300D03*
X213300Y146800D03*
X197300Y139100D03*
X205100Y147700D03*
X201500Y154400D03*
X197100Y160800D03*
X194600Y154800D03*
X227100Y43000D03*
X234200Y96300D03*
X225600Y104500D03*
X234500Y138700D03*
X230600Y146400D03*
X218100Y140500D03*
X224400Y138200D03*
X236800Y165000D03*
X238800Y157500D03*
X231600Y155100D03*
X221800Y149400D03*
X236500Y185900D03*
X235400Y172900D03*
X240300Y20200D03*
X243100Y49600D03*
X248600Y142900D03*
X242600Y140100D03*
X254400Y138200D03*
X239600Y148700D03*
X245100Y165200D03*
X255400Y148400D03*
X245600Y157000D03*
X248400Y149800D03*
X239800Y178700D03*
X243300Y185600D03*
X242300Y171800D03*
X252600Y192000D03*
X242400Y193300D03*
X270300Y20200D03*
X273100Y49600D03*
X264200Y96300D03*
X262900Y104900D03*
X284400Y138200D03*
X265300Y170000D03*
X282600Y192000D03*
X294200Y96300D03*
X287600Y150000D03*
X292800Y169800D03*
X324200Y96300D03*
X314600Y104100D03*
X310200Y135900D03*
X338300Y162900D03*
Y183800D03*
X359200Y164900D03*
X359100Y184400D03*
X806800Y26700D03*
X810700Y65200D03*
X836800Y26700D03*
X825200Y111700D03*
X840700Y65200D03*
X855200Y111700D03*
X855400Y173000D03*
X866800Y26700D03*
X870700Y65200D03*
X896800Y26700D03*
X900700Y65200D03*
X885200Y111700D03*
X885400Y173000D03*
X926800Y26700D03*
X915200Y111700D03*
X915400Y173000D03*
X930700Y65200D03*
X945200Y111700D03*
X945400Y173000D03*
X956800Y26700D03*
X960700Y65200D03*
X975200Y111700D03*
X975400Y173000D03*
X986800Y26700D03*
X990700Y65200D03*
X1018800Y26300D03*
X1005200Y111700D03*
X1005400Y173000D03*
X1022700Y64800D03*
X1037200Y111300D03*
X1035400Y173000D03*
X1048800Y26300D03*
X1052700Y64800D03*
X1067200Y111300D03*
X1067400Y172600D03*
X1078800Y26300D03*
X1082700Y64800D03*
X1097200Y111300D03*
X1097400Y172600D03*
X1136600Y19700D03*
X1135400Y41000D03*
X1127200Y111300D03*
X1127400Y172600D03*
X1157400D03*
G54D23*
G01X345900Y125100D02*
Y122198D01*
X349456Y118642D01*
X357210D01*
X375500Y100352D01*
Y37857D01*
X385700Y27657D01*
Y23900D01*
X395700Y13900D01*
X400100D01*
G01X350700Y121642D02*
X358454D01*
X378700Y101396D01*
Y38900D01*
X388700Y28900D01*
Y25200D01*
X396800Y17100D01*
X411900D01*
X412800Y16200D01*
G01X622200Y120258D02*
Y115943D01*
X612500Y106243D01*
Y92800D01*
X593147Y73447D01*
Y31440D01*
X576807Y15100D01*
X560950D01*
X559425Y13575D01*
G01X582416Y16466D02*
X596147Y30197D01*
Y72047D01*
X610700Y86600D01*
X616012D01*
X618000Y88588D01*
Y107500D01*
X622658Y112158D01*
G01X1219400Y123900D02*
X1225956D01*
X1229400Y120456D01*
Y106656D01*
X1246271Y89785D01*
Y32185D01*
X1264456Y14000D01*
X1268700D01*
G01X1219600Y129400D02*
X1224699D01*
X1232600Y121499D01*
Y107700D01*
X1249271Y91029D01*
Y33429D01*
X1265700Y17000D01*
X1284750D01*
X1289775Y11975D01*
G01X1492042Y126358D02*
Y121543D01*
X1482300Y111801D01*
Y91343D01*
X1463626Y72669D01*
Y31419D01*
X1450207Y18000D01*
X1433750D01*
X1429525Y13775D01*
G01X1492300Y117558D02*
X1487400Y112658D01*
Y92200D01*
X1466626Y71426D01*
Y29626D01*
X1454600Y17600D01*
G54D14*
X120500Y59400D03*
X114400Y59700D03*
X107500Y59500D03*
X102400Y59600D03*
X111958Y73600D03*
X116958Y68600D03*
X115400Y120270D03*
X119700Y132400D03*
X111500Y129900D03*
X132500Y110100D03*
X141400Y164800D03*
X129000D03*
X169200Y165200D03*
X155500Y164800D03*
X183300Y164700D03*
X346800Y113500D03*
X345400Y107600D03*
X346200Y102500D03*
X350700Y121642D03*
X345900Y125100D03*
X362500Y97100D03*
X357600Y97000D03*
X367200Y124000D03*
X400100Y13900D03*
X412800Y16200D03*
X466300Y100900D03*
X511600Y108000D03*
X525700Y99300D03*
X519400Y96400D03*
X559425Y13575D03*
X582416Y16466D03*
X604400Y96000D03*
X604200Y107400D03*
X626100Y99900D03*
X625600Y95400D03*
X625700Y90100D03*
X622658Y112158D03*
X622200Y120258D03*
X626600Y106100D03*
X651500Y94700D03*
X651100Y91100D03*
X661600Y75900D03*
X667200Y75700D03*
X670414Y96486D03*
X658400Y102500D03*
X659390Y117490D03*
X668839Y117661D03*
X667500Y126200D03*
X680300Y75600D03*
X698400Y90300D03*
X689723Y89400D03*
X689311Y96311D03*
X679862Y96538D03*
X678288Y122700D03*
X697185Y117385D03*
X687736Y118700D03*
X685600Y133200D03*
X680900D03*
X701100Y16900D03*
X701732Y101968D03*
X740300Y87300D03*
X735807Y96593D03*
X745256Y96044D03*
X743681Y117400D03*
X731950Y111850D03*
X723500Y118900D03*
X722400Y102300D03*
X730900Y108900D03*
X753100Y75100D03*
X765600Y74800D03*
X764153Y96153D03*
X754704Y96196D03*
X762578Y117300D03*
X753130D03*
X754300Y121400D03*
X764000Y124700D03*
X774600Y90300D03*
X776032Y101968D03*
X772027Y117300D03*
X1219600Y129400D03*
X1219400Y123900D03*
X1229800Y96400D03*
X1238900Y123300D03*
X1238100Y127900D03*
X1268700Y14000D03*
X1289775Y11975D03*
X1335600Y96500D03*
X1389900Y97600D03*
X1371600Y96000D03*
X1395200Y99500D03*
X1429525Y13775D03*
X1454600Y17600D03*
X1472400Y102700D03*
X1474200Y106600D03*
X1494200Y97800D03*
X1495000Y92800D03*
X1494700Y111200D03*
X1494500Y102700D03*
X1492300Y117558D03*
X1492042Y126358D03*
X1521579Y94700D03*
X1521179Y91100D03*
X1550500Y75500D03*
X1537279Y75700D03*
X1531679Y75900D03*
X1549940Y96538D03*
X1540492Y96486D03*
X1528478Y102500D03*
X1548366Y122700D03*
X1538917Y117661D03*
X1529468Y117490D03*
X1550979Y133200D03*
X1537579Y126200D03*
X1570800Y18900D03*
X1559802Y89400D03*
X1559389Y96311D03*
X1568479Y90300D03*
X1571810Y101968D03*
X1557814Y118700D03*
X1567263Y117385D03*
X1555679Y133200D03*
X1592900Y101700D03*
X1593300Y119000D03*
X1610379Y87300D03*
X1605885Y96593D03*
X1615334Y96044D03*
X1613759Y117400D03*
X1602028Y111850D03*
X1600900Y108700D03*
X1635679Y74800D03*
X1623179Y75100D03*
X1624782Y96196D03*
X1634231Y96153D03*
X1623208Y117300D03*
X1642105D03*
X1632656D03*
X1624300Y121500D03*
X1634179Y124300D03*
X1644679Y90300D03*
X1646110Y101968D03*
G54D24*
G01X457212Y-338900D02*
Y-343900D01*
G01X455755Y-338900D02*
X458669D01*
G01X463579Y-343900D02*
X461045D01*
Y-338900D01*
X463579D01*
G01X462565Y-341317D02*
X461045D01*
G01X466145Y-338900D02*
Y-343900D01*
X468679D01*
G01X472512Y-344067D02*
X472385Y-343983D01*
Y-343817D01*
X472512Y-343733D01*
X472639Y-343817D01*
Y-343983D01*
X472512Y-344067D01*
G01Y-341817D02*
X472385Y-341733D01*
Y-341567D01*
X472512Y-341483D01*
X472639Y-341567D01*
Y-341733D01*
X472512Y-341817D01*
G01X477295Y-345567D02*
X476662Y-344733D01*
X476345Y-343900D01*
Y-340567D01*
X476662Y-339733D01*
X477295Y-338900D01*
G01X482712D02*
X482205Y-339067D01*
X481825Y-339483D01*
X481572Y-339983D01*
X481382Y-340650D01*
X481319Y-341400D01*
X481382Y-342150D01*
X481572Y-342817D01*
X481825Y-343317D01*
X482205Y-343733D01*
X482712Y-343900D01*
X483219Y-343733D01*
X483599Y-343317D01*
X483852Y-342817D01*
X484042Y-342150D01*
X484105Y-341400D01*
X484042Y-340650D01*
X483852Y-339983D01*
X483599Y-339483D01*
X483219Y-339067D01*
X482712Y-338900D01*
G01X486419Y-342900D02*
X486799Y-343483D01*
X487305Y-343817D01*
X487875Y-343900D01*
X488382Y-343817D01*
X488889Y-343400D01*
X489205Y-342900D01*
X489269Y-342400D01*
X489142Y-341817D01*
X488699Y-341400D01*
X488255Y-341233D01*
X487685D01*
G01X488255D02*
X488635Y-340983D01*
X488952Y-340567D01*
X489079Y-340067D01*
X488952Y-339567D01*
X488635Y-339150D01*
X488065Y-338900D01*
X487495Y-338983D01*
X486925Y-339317D01*
G01X493229Y-345567D02*
X493862Y-344733D01*
X494179Y-343900D01*
Y-340567D01*
X493862Y-339733D01*
X493229Y-338900D01*
G01X496619Y-342900D02*
X496999Y-343483D01*
X497505Y-343817D01*
X498075Y-343900D01*
X498582Y-343817D01*
X499089Y-343400D01*
X499405Y-342900D01*
X499469Y-342400D01*
X499342Y-341817D01*
X498899Y-341400D01*
X498455Y-341233D01*
X497885D01*
G01X498455D02*
X498835Y-340983D01*
X499152Y-340567D01*
X499279Y-340067D01*
X499152Y-339567D01*
X498835Y-339150D01*
X498265Y-338900D01*
X497695Y-338983D01*
X497125Y-339317D01*
G01X501909Y-339733D02*
X502289Y-339233D01*
X502732Y-338983D01*
X503239Y-338900D01*
X503872Y-339067D01*
X504315Y-339483D01*
X504442Y-339983D01*
X504379Y-340483D01*
X504125Y-340900D01*
X502859Y-341733D01*
X502289Y-342317D01*
X501909Y-343150D01*
X501782Y-343900D01*
X504442D01*
G01X508085D02*
X508212Y-342817D01*
X508402Y-341900D01*
X508655Y-341067D01*
X508972Y-340150D01*
X509479Y-338900D01*
X506945D01*
G01X512489Y-342233D02*
X514135D01*
G01X517209Y-339733D02*
X517589Y-339233D01*
X518032Y-338983D01*
X518539Y-338900D01*
X519172Y-339067D01*
X519615Y-339483D01*
X519742Y-339983D01*
X519679Y-340483D01*
X519425Y-340900D01*
X518159Y-341733D01*
X517589Y-342317D01*
X517209Y-343150D01*
X517082Y-343900D01*
X519742D01*
G01X522119Y-342900D02*
X522499Y-343483D01*
X523005Y-343817D01*
X523575Y-343900D01*
X524082Y-343817D01*
X524589Y-343400D01*
X524905Y-342900D01*
X524969Y-342400D01*
X524842Y-341817D01*
X524399Y-341400D01*
X523955Y-341233D01*
X523385D01*
G01X523955D02*
X524335Y-340983D01*
X524652Y-340567D01*
X524779Y-340067D01*
X524652Y-339567D01*
X524335Y-339150D01*
X523765Y-338900D01*
X523195Y-338983D01*
X522625Y-339317D01*
G01X529372Y-343900D02*
Y-338900D01*
X527029Y-342483D01*
X530195D01*
G01X532319Y-343150D02*
X532699Y-343567D01*
X533142Y-343817D01*
X533712Y-343900D01*
X534282Y-343733D01*
X534725Y-343400D01*
X535042Y-342817D01*
X535105Y-342150D01*
X534979Y-341483D01*
X534662Y-341067D01*
X534219Y-340733D01*
X533775Y-340650D01*
X533332Y-340733D01*
X532762Y-341067D01*
X532952Y-338900D01*
X534662D01*
G01X542709Y-343900D02*
Y-338900D01*
X545115D01*
G01X544229Y-341317D02*
X542709D01*
G01X547429Y-343900D02*
X549012Y-338900D01*
X550595Y-343900D01*
G01X550025Y-342150D02*
X547999D01*
G01X552782Y-343900D02*
X555442Y-338900D01*
G01X552782D02*
X555442Y-343900D01*
G01X559212Y-344067D02*
X559085Y-343983D01*
Y-343817D01*
X559212Y-343733D01*
X559339Y-343817D01*
Y-343983D01*
X559212Y-344067D01*
G01Y-341817D02*
X559085Y-341733D01*
Y-341567D01*
X559212Y-341483D01*
X559339Y-341567D01*
Y-341733D01*
X559212Y-341817D01*
G01X563995Y-345567D02*
X563362Y-344733D01*
X563045Y-343900D01*
Y-340567D01*
X563362Y-339733D01*
X563995Y-338900D01*
G01X569412D02*
X568905Y-339067D01*
X568525Y-339483D01*
X568272Y-339983D01*
X568082Y-340650D01*
X568019Y-341400D01*
X568082Y-342150D01*
X568272Y-342817D01*
X568525Y-343317D01*
X568905Y-343733D01*
X569412Y-343900D01*
X569919Y-343733D01*
X570299Y-343317D01*
X570552Y-342817D01*
X570742Y-342150D01*
X570805Y-341400D01*
X570742Y-340650D01*
X570552Y-339983D01*
X570299Y-339483D01*
X569919Y-339067D01*
X569412Y-338900D01*
G01X573119Y-342900D02*
X573499Y-343483D01*
X574005Y-343817D01*
X574575Y-343900D01*
X575082Y-343817D01*
X575589Y-343400D01*
X575905Y-342900D01*
X575969Y-342400D01*
X575842Y-341817D01*
X575399Y-341400D01*
X574955Y-341233D01*
X574385D01*
G01X574955D02*
X575335Y-340983D01*
X575652Y-340567D01*
X575779Y-340067D01*
X575652Y-339567D01*
X575335Y-339150D01*
X574765Y-338900D01*
X574195Y-338983D01*
X573625Y-339317D01*
G01X579929Y-345567D02*
X580562Y-344733D01*
X580879Y-343900D01*
Y-340567D01*
X580562Y-339733D01*
X579929Y-338900D01*
G01X583319Y-342900D02*
X583699Y-343483D01*
X584205Y-343817D01*
X584775Y-343900D01*
X585282Y-343817D01*
X585789Y-343400D01*
X586105Y-342900D01*
X586169Y-342400D01*
X586042Y-341817D01*
X585599Y-341400D01*
X585155Y-341233D01*
X584585D01*
G01X585155D02*
X585535Y-340983D01*
X585852Y-340567D01*
X585979Y-340067D01*
X585852Y-339567D01*
X585535Y-339150D01*
X584965Y-338900D01*
X584395Y-338983D01*
X583825Y-339317D01*
G01X588735Y-343317D02*
X589179Y-343733D01*
X589685Y-343900D01*
X590192Y-343733D01*
X590635Y-343233D01*
X590952Y-342483D01*
X591079Y-341733D01*
Y-340817D01*
X590952Y-340067D01*
X590635Y-339400D01*
X590255Y-339067D01*
X589812Y-338900D01*
X589305Y-339067D01*
X588925Y-339400D01*
X588672Y-339900D01*
X588545Y-340567D01*
X588672Y-341150D01*
X588989Y-341733D01*
X589369Y-342067D01*
X589812Y-342150D01*
X590319Y-341983D01*
X590699Y-341567D01*
X591079Y-340817D01*
G01X594785Y-343900D02*
X594912Y-342817D01*
X595102Y-341900D01*
X595355Y-341067D01*
X595672Y-340150D01*
X596179Y-338900D01*
X593645D01*
G01X599189Y-342233D02*
X600835D01*
G01X603719Y-342900D02*
X604099Y-343483D01*
X604605Y-343817D01*
X605175Y-343900D01*
X605682Y-343817D01*
X606189Y-343400D01*
X606505Y-342900D01*
X606569Y-342400D01*
X606442Y-341817D01*
X605999Y-341400D01*
X605555Y-341233D01*
X604985D01*
G01X605555D02*
X605935Y-340983D01*
X606252Y-340567D01*
X606379Y-340067D01*
X606252Y-339567D01*
X605935Y-339150D01*
X605365Y-338900D01*
X604795Y-338983D01*
X604225Y-339317D01*
G01X609009Y-341817D02*
X609452Y-341233D01*
X609832Y-340900D01*
X610339Y-340733D01*
X610782Y-340900D01*
X611099Y-341233D01*
X611352Y-341733D01*
X611415Y-342317D01*
X611352Y-342817D01*
X611099Y-343317D01*
X610719Y-343733D01*
X610275Y-343900D01*
X609769Y-343733D01*
X609325Y-343233D01*
X609072Y-342483D01*
X609009Y-341650D01*
X609135Y-340567D01*
X609325Y-339983D01*
X609642Y-339400D01*
X610085Y-338983D01*
X610529Y-338900D01*
X610972Y-339067D01*
X611289Y-339483D01*
G01X615312Y-343900D02*
Y-338900D01*
X614552Y-339900D01*
G01Y-343900D02*
X616072D01*
G01X621172D02*
Y-338900D01*
X618829Y-342483D01*
X621995D01*
G01X445212Y-273900D02*
Y-348900D01*
X945212D01*
Y-273900D01*
X445212D01*
G01X640212D02*
Y-348900D01*
G01Y-323900D02*
X743212D01*
Y-298900D01*
G01X640212D02*
X743212D01*
G01Y-273900D02*
Y-348900D01*
G01X745212Y-273900D02*
Y-348900D01*
G01X750719Y-333900D02*
Y-328900D01*
X751985D01*
X752492Y-329150D01*
X752872Y-329483D01*
X753189Y-329983D01*
X753442Y-330567D01*
X753505Y-331400D01*
X753442Y-332233D01*
X753189Y-332817D01*
X752872Y-333317D01*
X752492Y-333650D01*
X751985Y-333900D01*
X750719D01*
G01X755629D02*
X757212Y-328900D01*
X758795Y-333900D01*
G01X758225Y-332150D02*
X756199D01*
G01X762312Y-328900D02*
Y-333900D01*
G01X760855Y-328900D02*
X763769D01*
G01X768679Y-333900D02*
X766145D01*
Y-328900D01*
X768679D01*
G01X767665Y-331317D02*
X766145D01*
G01X772512Y-334067D02*
X772385Y-333983D01*
Y-333817D01*
X772512Y-333733D01*
X772639Y-333817D01*
Y-333983D01*
X772512Y-334067D01*
G01Y-331817D02*
X772385Y-331733D01*
Y-331567D01*
X772512Y-331483D01*
X772639Y-331567D01*
Y-331733D01*
X772512Y-331817D01*
G01X745212Y-323900D02*
X945212D01*
G01X750845Y-308900D02*
Y-303900D01*
X752365D01*
X752872Y-304150D01*
X753252Y-304733D01*
X753379Y-305400D01*
X753252Y-306067D01*
X752935Y-306567D01*
X752365Y-306817D01*
X750845D01*
G01X756072Y-309067D02*
X758352Y-303900D01*
G01X760855Y-308900D02*
Y-303900D01*
X763769Y-308900D01*
Y-303900D01*
G01X767412Y-309067D02*
X767285Y-308983D01*
Y-308817D01*
X767412Y-308733D01*
X767539Y-308817D01*
Y-308983D01*
X767412Y-309067D01*
G01Y-306817D02*
X767285Y-306733D01*
Y-306567D01*
X767412Y-306483D01*
X767539Y-306567D01*
Y-306733D01*
X767412Y-306817D01*
G01X745212Y-298900D02*
X945212D01*
G01X750845Y-283900D02*
Y-278900D01*
X752365D01*
X752872Y-279150D01*
X753252Y-279733D01*
X753379Y-280400D01*
X753252Y-281067D01*
X752935Y-281567D01*
X752365Y-281817D01*
X750845D01*
G01X755945Y-283900D02*
Y-278900D01*
X757529D01*
X758035Y-279150D01*
X758352Y-279483D01*
X758479Y-280150D01*
X758352Y-280817D01*
X757972Y-281233D01*
X757529Y-281483D01*
X755945D01*
G01X757529D02*
X758479Y-283900D01*
G01X762312D02*
X761805Y-283817D01*
X761362Y-283483D01*
X760982Y-282983D01*
X760729Y-282400D01*
X760602Y-281733D01*
Y-281067D01*
X760729Y-280400D01*
X760982Y-279817D01*
X761362Y-279317D01*
X761805Y-278983D01*
X762312Y-278900D01*
X762819Y-278983D01*
X763262Y-279317D01*
X763642Y-279817D01*
X763895Y-280400D01*
X764022Y-281067D01*
Y-281733D01*
X763895Y-282400D01*
X763642Y-282983D01*
X763262Y-283483D01*
X762819Y-283817D01*
X762312Y-283900D01*
G01X766145Y-282900D02*
X766462Y-283400D01*
X766842Y-283733D01*
X767285Y-283900D01*
X767792Y-283733D01*
X768172Y-283400D01*
X768552Y-282900D01*
X768679Y-282233D01*
Y-278900D01*
G01X773779Y-283900D02*
X771245D01*
Y-278900D01*
X773779D01*
G01X772765Y-281317D02*
X771245D01*
G01X779005Y-279317D02*
X778625Y-279067D01*
X778182Y-278900D01*
X777675D01*
X777105Y-279150D01*
X776662Y-279567D01*
X776345Y-280067D01*
X776092Y-280900D01*
X776029Y-281650D01*
X776155Y-282400D01*
X776345Y-282900D01*
X776725Y-283400D01*
X777169Y-283733D01*
X777612Y-283900D01*
X778055D01*
X778499Y-283733D01*
X778879Y-283483D01*
X779195Y-283150D01*
G01X782712Y-278900D02*
Y-283900D01*
G01X781255Y-278900D02*
X784169D01*
G01X787812Y-284067D02*
X787685Y-283983D01*
Y-283817D01*
X787812Y-283733D01*
X787939Y-283817D01*
Y-283983D01*
X787812Y-284067D01*
G01Y-281817D02*
X787685Y-281733D01*
Y-281567D01*
X787812Y-281483D01*
X787939Y-281567D01*
Y-281733D01*
X787812Y-281817D01*
G01X860212Y-323900D02*
Y-348900D01*
G01X865845Y-333900D02*
Y-328900D01*
X867429D01*
X867935Y-329150D01*
X868252Y-329483D01*
X868379Y-330150D01*
X868252Y-330817D01*
X867872Y-331233D01*
X867429Y-331483D01*
X865845D01*
G01X867429D02*
X868379Y-333900D01*
G01X873479D02*
X870945D01*
Y-328900D01*
X873479D01*
G01X872465Y-331317D02*
X870945D01*
G01X875729Y-328900D02*
X877312Y-333900D01*
X878895Y-328900D01*
G01X882412Y-334067D02*
X882285Y-333983D01*
Y-333817D01*
X882412Y-333733D01*
X882539Y-333817D01*
Y-333983D01*
X882412Y-334067D01*
G01Y-331817D02*
X882285Y-331733D01*
Y-331567D01*
X882412Y-331483D01*
X882539Y-331567D01*
Y-331733D01*
X882412Y-331817D01*
G01X909212Y-323900D02*
Y-348900D01*
G01X-471400Y-391900D02*
Y1528800D01*
X2244200D01*
Y-391900D01*
X-471400D01*
G01X455917Y-335560D02*
X456544Y-336085D01*
X457249Y-336400D01*
X457875D01*
X458502Y-336085D01*
X458972Y-335560D01*
X459207Y-334825D01*
X459050Y-334090D01*
X458659Y-333460D01*
X457954Y-333040D01*
X457014Y-332830D01*
X456465Y-332410D01*
X456230Y-331675D01*
X456387Y-330940D01*
X456779Y-330415D01*
X457327Y-330100D01*
X457875D01*
X458424Y-330310D01*
X458894Y-330835D01*
G01X462217Y-336400D02*
Y-330100D01*
G01X465507D02*
Y-336400D01*
G01Y-333250D02*
X462217D01*
G01X469222Y-330100D02*
X471102D01*
G01X470162D02*
Y-336400D01*
G01X469222D02*
X471102D01*
G01X478029D02*
X474895D01*
Y-330100D01*
X478029D01*
G01X476775Y-333145D02*
X474895D01*
G01X480960Y-336400D02*
Y-330100D01*
X484564Y-336400D01*
Y-330100D01*
G01X488905Y-337555D02*
X489219Y-336190D01*
G01X495362Y-330100D02*
Y-336400D01*
G01X493560Y-330100D02*
X497164D01*
G01X499704Y-336400D02*
X501662Y-330100D01*
X503620Y-336400D01*
G01X502915Y-334195D02*
X500409D01*
G01X507022Y-330100D02*
X508902D01*
G01X507962D02*
Y-336400D01*
G01X507022D02*
X508902D01*
G01X511912Y-330100D02*
X513009Y-336400D01*
X514262Y-330100D01*
X515515Y-336400D01*
X516612Y-330100D01*
G01X518604Y-336400D02*
X520562Y-330100D01*
X522520Y-336400D01*
G01X521815Y-334195D02*
X519309D01*
G01X525060Y-336400D02*
Y-330100D01*
X528664Y-336400D01*
Y-330100D01*
G01X537895Y-336400D02*
Y-330100D01*
X539854D01*
X540480Y-330415D01*
X540872Y-330835D01*
X541029Y-331675D01*
X540872Y-332515D01*
X540402Y-333040D01*
X539854Y-333355D01*
X537895D01*
G01X539854D02*
X541029Y-336400D01*
G01X545762Y-336610D02*
X545605Y-336505D01*
Y-336295D01*
X545762Y-336190D01*
X545919Y-336295D01*
Y-336505D01*
X545762Y-336610D01*
G01X552062Y-336400D02*
X551435Y-336295D01*
X550887Y-335875D01*
X550417Y-335245D01*
X550104Y-334510D01*
X549947Y-333670D01*
Y-332830D01*
X550104Y-331990D01*
X550417Y-331255D01*
X550887Y-330625D01*
X551435Y-330205D01*
X552062Y-330100D01*
X552689Y-330205D01*
X553237Y-330625D01*
X553707Y-331255D01*
X554020Y-331990D01*
X554177Y-332830D01*
Y-333670D01*
X554020Y-334510D01*
X553707Y-335245D01*
X553237Y-335875D01*
X552689Y-336295D01*
X552062Y-336400D01*
G01X558362Y-336610D02*
X558205Y-336505D01*
Y-336295D01*
X558362Y-336190D01*
X558519Y-336295D01*
Y-336505D01*
X558362Y-336610D01*
G01X566385Y-330625D02*
X565915Y-330310D01*
X565367Y-330100D01*
X564740D01*
X564035Y-330415D01*
X563487Y-330940D01*
X563095Y-331570D01*
X562782Y-332620D01*
X562704Y-333565D01*
X562860Y-334510D01*
X563095Y-335140D01*
X563565Y-335770D01*
X564114Y-336190D01*
X564662Y-336400D01*
X565210D01*
X565759Y-336190D01*
X566229Y-335875D01*
X566620Y-335455D01*
G01X570962Y-336610D02*
X570805Y-336505D01*
Y-336295D01*
X570962Y-336190D01*
X571119Y-336295D01*
Y-336505D01*
X570962Y-336610D01*
G01X455839Y-326400D02*
Y-320100D01*
G01X458815D02*
X455839Y-323985D01*
G01X459285Y-326400D02*
X457170Y-322200D01*
G01X462139Y-320100D02*
Y-324615D01*
X462452Y-325560D01*
X463079Y-326190D01*
X463862Y-326400D01*
X464645Y-326190D01*
X465272Y-325560D01*
X465585Y-324615D01*
Y-320100D01*
G01X471729Y-326400D02*
X468595D01*
Y-320100D01*
X471729D01*
G01X470475Y-323145D02*
X468595D01*
G01X475522Y-320100D02*
X477402D01*
G01X476462D02*
Y-326400D01*
G01X475522D02*
X477402D01*
G01X487417Y-325560D02*
X488044Y-326085D01*
X488749Y-326400D01*
X489375D01*
X490002Y-326085D01*
X490472Y-325560D01*
X490707Y-324825D01*
X490550Y-324090D01*
X490159Y-323460D01*
X489454Y-323040D01*
X488514Y-322830D01*
X487965Y-322410D01*
X487730Y-321675D01*
X487887Y-320940D01*
X488279Y-320415D01*
X488827Y-320100D01*
X489375D01*
X489924Y-320310D01*
X490394Y-320835D01*
G01X493717Y-326400D02*
Y-320100D01*
G01X497007D02*
Y-326400D01*
G01Y-323250D02*
X493717D01*
G01X499704Y-326400D02*
X501662Y-320100D01*
X503620Y-326400D01*
G01X502915Y-324195D02*
X500409D01*
G01X506160Y-326400D02*
Y-320100D01*
X509764Y-326400D01*
Y-320100D01*
G01X518917Y-326400D02*
Y-320100D01*
G01X522207D02*
Y-326400D01*
G01Y-323250D02*
X518917D01*
G01X525217Y-325560D02*
X525844Y-326085D01*
X526549Y-326400D01*
X527175D01*
X527802Y-326085D01*
X528272Y-325560D01*
X528507Y-324825D01*
X528350Y-324090D01*
X527959Y-323460D01*
X527254Y-323040D01*
X526314Y-322830D01*
X525765Y-322410D01*
X525530Y-321675D01*
X525687Y-320940D01*
X526079Y-320415D01*
X526627Y-320100D01*
X527175D01*
X527724Y-320310D01*
X528194Y-320835D01*
G01X532222Y-320100D02*
X534102D01*
G01X533162D02*
Y-326400D01*
G01X532222D02*
X534102D01*
G01X537504D02*
X539462Y-320100D01*
X541420Y-326400D01*
G01X540715Y-324195D02*
X538209D01*
G01X543960Y-326400D02*
Y-320100D01*
X547564Y-326400D01*
Y-320100D01*
G01X552532Y-323250D02*
X554099D01*
Y-325140D01*
X553629Y-325770D01*
X553080Y-326190D01*
X552297Y-326400D01*
X551514Y-326190D01*
X550965Y-325770D01*
X550495Y-325140D01*
X550182Y-324405D01*
X550025Y-323565D01*
Y-322830D01*
X550182Y-322200D01*
X550495Y-321465D01*
X550965Y-320835D01*
X551435Y-320415D01*
X552062Y-320100D01*
X552610D01*
X553237Y-320310D01*
X553707Y-320730D01*
G01X558205Y-327555D02*
X558519Y-326190D01*
G01X564662Y-320100D02*
Y-326400D01*
G01X562860Y-320100D02*
X566464D01*
G01X569004Y-326400D02*
X570962Y-320100D01*
X572920Y-326400D01*
G01X572215Y-324195D02*
X569709D01*
G01X577262Y-326400D02*
X576635Y-326295D01*
X576087Y-325875D01*
X575617Y-325245D01*
X575304Y-324510D01*
X575147Y-323670D01*
Y-322830D01*
X575304Y-321990D01*
X575617Y-321255D01*
X576087Y-320625D01*
X576635Y-320205D01*
X577262Y-320100D01*
X577889Y-320205D01*
X578437Y-320625D01*
X578907Y-321255D01*
X579220Y-321990D01*
X579377Y-322830D01*
Y-323670D01*
X579220Y-324510D01*
X578907Y-325245D01*
X578437Y-325875D01*
X577889Y-326295D01*
X577262Y-326400D01*
G01X589862D02*
Y-323565D01*
X588295Y-320100D01*
G01X591429D02*
X589862Y-323565D01*
G01X594439Y-320100D02*
Y-324615D01*
X594752Y-325560D01*
X595379Y-326190D01*
X596162Y-326400D01*
X596945Y-326190D01*
X597572Y-325560D01*
X597885Y-324615D01*
Y-320100D01*
G01X600504Y-326400D02*
X602462Y-320100D01*
X604420Y-326400D01*
G01X603715Y-324195D02*
X601209D01*
G01X606960Y-326400D02*
Y-320100D01*
X610564Y-326400D01*
Y-320100D01*
G01X455760Y-316400D02*
Y-310100D01*
X459364Y-316400D01*
Y-310100D01*
G01X463862Y-316400D02*
X463235Y-316295D01*
X462687Y-315875D01*
X462217Y-315245D01*
X461904Y-314510D01*
X461747Y-313670D01*
Y-312830D01*
X461904Y-311990D01*
X462217Y-311255D01*
X462687Y-310625D01*
X463235Y-310205D01*
X463862Y-310100D01*
X464489Y-310205D01*
X465037Y-310625D01*
X465507Y-311255D01*
X465820Y-311990D01*
X465977Y-312830D01*
Y-313670D01*
X465820Y-314510D01*
X465507Y-315245D01*
X465037Y-315875D01*
X464489Y-316295D01*
X463862Y-316400D01*
G01X470162Y-316610D02*
X470005Y-316505D01*
Y-316295D01*
X470162Y-316190D01*
X470319Y-316295D01*
Y-316505D01*
X470162Y-316610D01*
G01X476462Y-316400D02*
Y-310100D01*
X475522Y-311360D01*
G01Y-316400D02*
X477402D01*
G01X482762D02*
X483310Y-316295D01*
X483937Y-315980D01*
X484329Y-315455D01*
X484485Y-314720D01*
X484329Y-313985D01*
X483859Y-313355D01*
X483154Y-313040D01*
X482370D01*
X481900Y-312830D01*
X481509Y-312305D01*
X481352Y-311570D01*
X481587Y-310835D01*
X482135Y-310310D01*
X482762Y-310100D01*
X483389Y-310310D01*
X483937Y-310835D01*
X484172Y-311570D01*
X484015Y-312305D01*
X483624Y-312830D01*
X483154Y-313040D01*
X482370D01*
X481665Y-313355D01*
X481195Y-313985D01*
X481039Y-314720D01*
X481195Y-315455D01*
X481587Y-315980D01*
X482214Y-316295D01*
X482762Y-316400D01*
G01X489062D02*
X489610Y-316295D01*
X490237Y-315980D01*
X490629Y-315455D01*
X490785Y-314720D01*
X490629Y-313985D01*
X490159Y-313355D01*
X489454Y-313040D01*
X488670D01*
X488200Y-312830D01*
X487809Y-312305D01*
X487652Y-311570D01*
X487887Y-310835D01*
X488435Y-310310D01*
X489062Y-310100D01*
X489689Y-310310D01*
X490237Y-310835D01*
X490472Y-311570D01*
X490315Y-312305D01*
X489924Y-312830D01*
X489454Y-313040D01*
X488670D01*
X487965Y-313355D01*
X487495Y-313985D01*
X487339Y-314720D01*
X487495Y-315455D01*
X487887Y-315980D01*
X488514Y-316295D01*
X489062Y-316400D01*
G01X495205Y-317555D02*
X495519Y-316190D01*
G01X499312Y-310100D02*
X500409Y-316400D01*
X501662Y-310100D01*
X502915Y-316400D01*
X504012Y-310100D01*
G01X509529Y-316400D02*
X506395D01*
Y-310100D01*
X509529D01*
G01X508275Y-313145D02*
X506395D01*
G01X512460Y-316400D02*
Y-310100D01*
X516064Y-316400D01*
Y-310100D01*
G01X525217Y-316400D02*
Y-310100D01*
G01X528507D02*
Y-316400D01*
G01Y-313250D02*
X525217D01*
G01X530812Y-310100D02*
X531909Y-316400D01*
X533162Y-310100D01*
X534415Y-316400D01*
X535512Y-310100D01*
G01X537504Y-316400D02*
X539462Y-310100D01*
X541420Y-316400D01*
G01X540715Y-314195D02*
X538209D01*
G01X550574Y-311150D02*
X551044Y-310520D01*
X551592Y-310205D01*
X552219Y-310100D01*
X553002Y-310310D01*
X553550Y-310835D01*
X553707Y-311465D01*
X553629Y-312095D01*
X553315Y-312620D01*
X551749Y-313670D01*
X551044Y-314405D01*
X550574Y-315455D01*
X550417Y-316400D01*
X553707D01*
G01X556560D02*
Y-310100D01*
X560164Y-316400D01*
Y-310100D01*
G01X562939Y-316400D02*
Y-310100D01*
X564505D01*
X565132Y-310415D01*
X565602Y-310835D01*
X565994Y-311465D01*
X566307Y-312200D01*
X566385Y-313250D01*
X566307Y-314300D01*
X565994Y-315035D01*
X565602Y-315665D01*
X565132Y-316085D01*
X564505Y-316400D01*
X562939D01*
G01X575695D02*
Y-310100D01*
X577654D01*
X578280Y-310415D01*
X578672Y-310835D01*
X578829Y-311675D01*
X578672Y-312515D01*
X578202Y-313040D01*
X577654Y-313355D01*
X575695D01*
G01X577654D02*
X578829Y-316400D01*
G01X581839D02*
Y-310100D01*
X583405D01*
X584032Y-310415D01*
X584502Y-310835D01*
X584894Y-311465D01*
X585207Y-312200D01*
X585285Y-313250D01*
X585207Y-314300D01*
X584894Y-315035D01*
X584502Y-315665D01*
X584032Y-316085D01*
X583405Y-316400D01*
X581839D01*
G01X589862Y-316610D02*
X589705Y-316505D01*
Y-316295D01*
X589862Y-316190D01*
X590019Y-316295D01*
Y-316505D01*
X589862Y-316610D01*
G01X498859Y115666D02*
X500732Y119413D01*
X500463Y120218D01*
X499694Y120602D01*
X498800Y121497D01*
Y127637D01*
X494137Y132300D01*
X471963D01*
X464800Y125137D01*
Y114663D01*
X472400Y107063D01*
Y69200D01*
X471410Y68210D01*
Y17610D01*
X469142Y15342D01*
X467300D01*
X466654Y14696D01*
Y13386D01*
G01X503859Y125666D02*
X501984Y121917D01*
X501179Y121650D01*
X500642Y121918D01*
X500400Y122160D01*
Y128300D01*
X494800Y133900D01*
X471300D01*
X463200Y125800D01*
Y114000D01*
X470800Y106400D01*
Y69863D01*
X469810Y68873D01*
Y18273D01*
X468479Y16942D01*
X467300D01*
X466654Y17588D01*
Y18898D01*
G01X479862Y-303700D02*
X477342Y-303283D01*
X475137Y-301617D01*
X473247Y-299117D01*
X471987Y-296200D01*
X471357Y-292867D01*
Y-289533D01*
X471987Y-286200D01*
X473247Y-283283D01*
X475137Y-280784D01*
X477342Y-279117D01*
X479862Y-278700D01*
X482382Y-279117D01*
X484587Y-280784D01*
X486477Y-283283D01*
X487737Y-286200D01*
X488367Y-289533D01*
Y-292867D01*
X487737Y-296200D01*
X486477Y-299117D01*
X484587Y-301617D01*
X482382Y-303283D01*
X479862Y-303700D01*
G01X482382Y-297033D02*
X486162Y-303700D01*
G01X499707Y-287034D02*
Y-298700D01*
X500967Y-301617D01*
X502857Y-303283D01*
X505062Y-303700D01*
X507267Y-303283D01*
X509157Y-301617D01*
X510417Y-298700D01*
G01Y-303700D02*
Y-287034D01*
G01X535932Y-303700D02*
Y-287034D01*
G01Y-289950D02*
X534672Y-288284D01*
X532782Y-287450D01*
X530577Y-287034D01*
X528372Y-287867D01*
X526482Y-289533D01*
X525222Y-292034D01*
X524592Y-295367D01*
X525222Y-298700D01*
X526482Y-301201D01*
X528372Y-302867D01*
X530577Y-303700D01*
X532782Y-303283D01*
X534672Y-302034D01*
X535932Y-300367D01*
G01X550107Y-303700D02*
Y-287034D01*
G01Y-291200D02*
X551367Y-289117D01*
X553257Y-287450D01*
X555777Y-287034D01*
X557982Y-287450D01*
X559872Y-289117D01*
X560817Y-292034D01*
Y-303700D01*
G01X580662Y-278700D02*
Y-303700D01*
G01X576252Y-287034D02*
X585072D01*
G01X611532Y-303700D02*
Y-287034D01*
G01Y-289950D02*
X610272Y-288284D01*
X608382Y-287450D01*
X606177Y-287034D01*
X603972Y-287867D01*
X602082Y-289533D01*
X600822Y-292034D01*
X600192Y-295367D01*
X600822Y-298700D01*
X602082Y-301201D01*
X603972Y-302867D01*
X606177Y-303700D01*
X608382Y-303283D01*
X610272Y-302034D01*
X611532Y-300367D01*
G01X490276Y13780D02*
Y12200D01*
X489900Y11824D01*
X487720D01*
X487120Y12424D01*
Y56720D01*
X495100Y64700D01*
Y99337D01*
X510500Y114737D01*
Y132700D01*
X509500Y133700D01*
Y155200D01*
X506500Y158200D01*
X471737D01*
X467900Y154363D01*
Y148381D01*
X469694Y146586D01*
X469926Y146470D01*
X470463Y146202D01*
X470732Y145397D01*
X468859Y141650D01*
G01X490276Y8268D02*
Y9624D01*
X489676Y10224D01*
X487057D01*
X485520Y11761D01*
Y57383D01*
X493500Y65363D01*
Y71906D01*
X492900Y72506D01*
Y74306D01*
X493500Y74906D01*
Y76706D01*
X492900Y77306D01*
Y79106D01*
X493500Y79706D01*
Y81506D01*
X492900Y82106D01*
Y83906D01*
X493500Y84506D01*
Y86306D01*
X492900Y86906D01*
Y88706D01*
X493500Y89306D01*
Y100000D01*
X508900Y115400D01*
Y132037D01*
X507900Y133037D01*
Y154537D01*
X505837Y156600D01*
X472400D01*
X469500Y153700D01*
Y149044D01*
X470642Y147902D01*
X471179Y147634D01*
X471984Y147901D01*
X473859Y151650D01*
G01X478859Y115666D02*
X483566D01*
X484600Y116700D01*
Y118800D01*
X483800Y119600D01*
X476263D01*
X474200Y117537D01*
Y114663D01*
X483600Y105263D01*
Y77937D01*
X479000Y73337D01*
Y11900D01*
X477324Y10224D01*
X475300D01*
X474528Y9452D01*
Y8268D01*
G01X493859Y125666D02*
X489393Y121200D01*
X475600D01*
X472600Y118200D01*
Y114000D01*
X482000Y104600D01*
Y78600D01*
X477400Y74000D01*
Y12563D01*
X476661Y11824D01*
X475176D01*
X474528Y12472D01*
Y13780D01*
G01X651212Y-283400D02*
Y-291400D01*
X655212D01*
G01X663012D02*
Y-286067D01*
G01Y-287000D02*
X662612Y-286467D01*
X662012Y-286200D01*
X661312Y-286067D01*
X660612Y-286333D01*
X660012Y-286867D01*
X659612Y-287667D01*
X659412Y-288733D01*
X659612Y-289800D01*
X660012Y-290600D01*
X660612Y-291133D01*
X661312Y-291400D01*
X662012Y-291267D01*
X662612Y-290867D01*
X663012Y-290334D01*
G01X667112Y-293800D02*
X667712Y-294067D01*
X668512Y-293800D01*
X669012Y-293267D01*
X669412Y-292600D01*
X670012Y-290467D01*
X671312Y-286067D01*
G01X668112D02*
X670012Y-290467D01*
G01X675712Y-287800D02*
X678912D01*
X678612Y-286867D01*
X678112Y-286333D01*
X677412Y-286067D01*
X676712Y-286200D01*
X676112Y-286600D01*
X675712Y-287533D01*
X675512Y-288334D01*
Y-289133D01*
X675712Y-289933D01*
X676212Y-290733D01*
X676812Y-291267D01*
X677512Y-291400D01*
X678212Y-291133D01*
X678912Y-290334D01*
G01X683812Y-291400D02*
Y-286067D01*
G01Y-287133D02*
X684312Y-286600D01*
X684812Y-286200D01*
X685512Y-286067D01*
X686012Y-286200D01*
X686612Y-286600D01*
G01X673512Y-333400D02*
X675912D01*
G01X674712D02*
Y-341400D01*
G01X673512D02*
X675912D01*
G01X681312D02*
Y-336067D01*
G01Y-337133D02*
X681812Y-336600D01*
X682312Y-336200D01*
X683012Y-336067D01*
X683512Y-336200D01*
X684112Y-336600D01*
G01X689212Y-337800D02*
X692412D01*
X692112Y-336867D01*
X691612Y-336333D01*
X690912Y-336067D01*
X690212Y-336200D01*
X689612Y-336600D01*
X689212Y-337533D01*
X689012Y-338334D01*
Y-339133D01*
X689212Y-339933D01*
X689712Y-340733D01*
X690312Y-341267D01*
X691012Y-341400D01*
X691712Y-341133D01*
X692412Y-340334D01*
G01X697012Y-341400D02*
Y-336067D01*
G01Y-337400D02*
X697412Y-336733D01*
X698012Y-336200D01*
X698812Y-336067D01*
X699512Y-336200D01*
X700112Y-336733D01*
X700412Y-337667D01*
Y-341400D01*
G01X705212Y-337800D02*
X708412D01*
X708112Y-336867D01*
X707612Y-336333D01*
X706912Y-336067D01*
X706212Y-336200D01*
X705612Y-336600D01*
X705212Y-337533D01*
X705012Y-338334D01*
Y-339133D01*
X705212Y-339933D01*
X705712Y-340733D01*
X706312Y-341267D01*
X707012Y-341400D01*
X707712Y-341133D01*
X708412Y-340334D01*
G01X681012Y-308400D02*
X683412D01*
G01X682212D02*
Y-316400D01*
G01X681012D02*
X683412D01*
G01X687912D02*
Y-308400D01*
X692512Y-316400D01*
Y-308400D01*
G01X698212Y-316400D02*
Y-308400D01*
X697012Y-310000D01*
G01Y-316400D02*
X699412D01*
G01X702512Y-289800D02*
X703112Y-290733D01*
X703912Y-291267D01*
X704812Y-291400D01*
X705612Y-291267D01*
X706412Y-290600D01*
X706912Y-289800D01*
X707012Y-289000D01*
X706812Y-288067D01*
X706112Y-287400D01*
X705412Y-287133D01*
X704512D01*
G01X705412D02*
X706012Y-286733D01*
X706512Y-286067D01*
X706712Y-285267D01*
X706512Y-284467D01*
X706012Y-283800D01*
X705112Y-283400D01*
X704212Y-283533D01*
X703312Y-284067D01*
G01X777812Y-334733D02*
X778412Y-333933D01*
X779112Y-333533D01*
X779912Y-333400D01*
X780912Y-333667D01*
X781612Y-334333D01*
X781812Y-335133D01*
X781712Y-335934D01*
X781312Y-336600D01*
X779312Y-337933D01*
X778412Y-338867D01*
X777812Y-340200D01*
X777612Y-341400D01*
X781812D01*
G01X787712Y-333400D02*
X786912Y-333667D01*
X786312Y-334333D01*
X785912Y-335133D01*
X785612Y-336200D01*
X785512Y-337400D01*
X785612Y-338600D01*
X785912Y-339667D01*
X786312Y-340467D01*
X786912Y-341133D01*
X787712Y-341400D01*
X788512Y-341133D01*
X789112Y-340467D01*
X789512Y-339667D01*
X789812Y-338600D01*
X789912Y-337400D01*
X789812Y-336200D01*
X789512Y-335133D01*
X789112Y-334333D01*
X788512Y-333667D01*
X787712Y-333400D01*
G01X795712Y-341400D02*
Y-333400D01*
X794512Y-335000D01*
G01Y-341400D02*
X796912D01*
G01X801812Y-334733D02*
X802412Y-333933D01*
X803112Y-333533D01*
X803912Y-333400D01*
X804912Y-333667D01*
X805612Y-334333D01*
X805812Y-335133D01*
X805712Y-335934D01*
X805312Y-336600D01*
X803312Y-337933D01*
X802412Y-338867D01*
X801812Y-340200D01*
X801612Y-341400D01*
X805812D01*
G01X809912Y-341667D02*
X813512Y-333400D01*
G01X819712Y-341400D02*
Y-333400D01*
X818512Y-335000D01*
G01Y-341400D02*
X820912D01*
G01X827712Y-333400D02*
X826912Y-333667D01*
X826312Y-334333D01*
X825912Y-335133D01*
X825612Y-336200D01*
X825512Y-337400D01*
X825612Y-338600D01*
X825912Y-339667D01*
X826312Y-340467D01*
X826912Y-341133D01*
X827712Y-341400D01*
X828512Y-341133D01*
X829112Y-340467D01*
X829512Y-339667D01*
X829812Y-338600D01*
X829912Y-337400D01*
X829812Y-336200D01*
X829512Y-335133D01*
X829112Y-334333D01*
X828512Y-333667D01*
X827712Y-333400D01*
G01X833912Y-341667D02*
X837512Y-333400D01*
G01X841512Y-339800D02*
X842112Y-340733D01*
X842912Y-341267D01*
X843812Y-341400D01*
X844612Y-341267D01*
X845412Y-340600D01*
X845912Y-339800D01*
X846012Y-339000D01*
X845812Y-338067D01*
X845112Y-337400D01*
X844412Y-337133D01*
X843512D01*
G01X844412D02*
X845012Y-336733D01*
X845512Y-336067D01*
X845712Y-335267D01*
X845512Y-334467D01*
X845012Y-333800D01*
X844112Y-333400D01*
X843212Y-333533D01*
X842312Y-334067D01*
G01X851712Y-341400D02*
Y-333400D01*
X850512Y-335000D01*
G01Y-341400D02*
X852912D01*
G01X777512Y-316400D02*
Y-308400D01*
X779512D01*
X780312Y-308800D01*
X780912Y-309333D01*
X781412Y-310133D01*
X781812Y-311067D01*
X781912Y-312400D01*
X781812Y-313733D01*
X781412Y-314667D01*
X780912Y-315467D01*
X780312Y-316000D01*
X779512Y-316400D01*
X777512D01*
G01X785212D02*
X787712Y-308400D01*
X790212Y-316400D01*
G01X789312Y-313600D02*
X786112D01*
G01X795712Y-308400D02*
X794912Y-308667D01*
X794312Y-309333D01*
X793912Y-310133D01*
X793612Y-311200D01*
X793512Y-312400D01*
X793612Y-313600D01*
X793912Y-314667D01*
X794312Y-315467D01*
X794912Y-316133D01*
X795712Y-316400D01*
X796512Y-316133D01*
X797112Y-315467D01*
X797512Y-314667D01*
X797812Y-313600D01*
X797912Y-312400D01*
X797812Y-311200D01*
X797512Y-310133D01*
X797112Y-309333D01*
X796512Y-308667D01*
X795712Y-308400D01*
G01X803712D02*
Y-316400D01*
G01X801412Y-308400D02*
X806012D01*
G01X809812Y-313067D02*
X810512Y-312133D01*
X811112Y-311600D01*
X811912Y-311333D01*
X812612Y-311600D01*
X813112Y-312133D01*
X813512Y-312933D01*
X813612Y-313867D01*
X813512Y-314667D01*
X813112Y-315467D01*
X812512Y-316133D01*
X811812Y-316400D01*
X811012Y-316133D01*
X810312Y-315334D01*
X809912Y-314133D01*
X809812Y-312800D01*
X810012Y-311067D01*
X810312Y-310133D01*
X810812Y-309200D01*
X811512Y-308533D01*
X812212Y-308400D01*
X812912Y-308667D01*
X813412Y-309333D01*
G01X817112Y-316400D02*
Y-308400D01*
X819712Y-315067D01*
X822312Y-308400D01*
Y-316400D01*
G01X827712Y-308400D02*
Y-316400D01*
G01X825412Y-308400D02*
X830012D01*
G01X833612Y-316400D02*
Y-308400D01*
G01X837812D02*
Y-316400D01*
G01Y-312400D02*
X833612D01*
G01X843712Y-316400D02*
X844412Y-316267D01*
X845212Y-315867D01*
X845712Y-315200D01*
X845912Y-314267D01*
X845712Y-313334D01*
X845112Y-312533D01*
X844212Y-312133D01*
X843212D01*
X842612Y-311867D01*
X842112Y-311200D01*
X841912Y-310267D01*
X842212Y-309333D01*
X842912Y-308667D01*
X843712Y-308400D01*
X844512Y-308667D01*
X845212Y-309333D01*
X845512Y-310267D01*
X845312Y-311200D01*
X844812Y-311867D01*
X844212Y-312133D01*
X843212D01*
X842312Y-312533D01*
X841712Y-313334D01*
X841512Y-314267D01*
X841712Y-315200D01*
X842212Y-315867D01*
X843012Y-316267D01*
X843712Y-316400D01*
G01X853912Y-309067D02*
X853312Y-308667D01*
X852612Y-308400D01*
X851812D01*
X850912Y-308800D01*
X850212Y-309467D01*
X849712Y-310267D01*
X849312Y-311600D01*
X849212Y-312800D01*
X849412Y-314000D01*
X849712Y-314800D01*
X850312Y-315600D01*
X851012Y-316133D01*
X851712Y-316400D01*
X852412D01*
X853112Y-316133D01*
X853712Y-315733D01*
X854212Y-315200D01*
G01X859712Y-308400D02*
X858912Y-308667D01*
X858312Y-309333D01*
X857912Y-310133D01*
X857612Y-311200D01*
X857512Y-312400D01*
X857612Y-313600D01*
X857912Y-314667D01*
X858312Y-315467D01*
X858912Y-316133D01*
X859712Y-316400D01*
X860512Y-316133D01*
X861112Y-315467D01*
X861512Y-314667D01*
X861812Y-313600D01*
X861912Y-312400D01*
X861812Y-311200D01*
X861512Y-310133D01*
X861112Y-309333D01*
X860512Y-308667D01*
X859712Y-308400D01*
G01X799712Y-283400D02*
Y-291400D01*
G01X797412Y-283400D02*
X802012D01*
G01X805812Y-288067D02*
X806512Y-287133D01*
X807112Y-286600D01*
X807912Y-286333D01*
X808612Y-286600D01*
X809112Y-287133D01*
X809512Y-287933D01*
X809612Y-288867D01*
X809512Y-289667D01*
X809112Y-290467D01*
X808512Y-291133D01*
X807812Y-291400D01*
X807012Y-291133D01*
X806312Y-290334D01*
X805912Y-289133D01*
X805812Y-287800D01*
X806012Y-286067D01*
X806312Y-285133D01*
X806812Y-284200D01*
X807512Y-283533D01*
X808212Y-283400D01*
X808912Y-283667D01*
X809412Y-284333D01*
G01X813112Y-291400D02*
Y-283400D01*
X815712Y-290067D01*
X818312Y-283400D01*
Y-291400D01*
G01X820712Y-294067D02*
X826712D01*
G01X831712Y-283400D02*
Y-291400D01*
G01X829412Y-283400D02*
X834012D01*
G01X838312Y-291400D02*
Y-286067D01*
G01Y-287133D02*
X838812Y-286600D01*
X839312Y-286200D01*
X840012Y-286067D01*
X840512Y-286200D01*
X841112Y-286600D01*
G01X849512Y-291400D02*
Y-286067D01*
G01Y-287000D02*
X849112Y-286467D01*
X848512Y-286200D01*
X847812Y-286067D01*
X847112Y-286333D01*
X846512Y-286867D01*
X846112Y-287667D01*
X845912Y-288733D01*
X846112Y-289800D01*
X846512Y-290600D01*
X847112Y-291133D01*
X847812Y-291400D01*
X848512Y-291267D01*
X849112Y-290867D01*
X849512Y-290334D01*
G01X853612Y-293800D02*
X854212Y-294067D01*
X855012Y-293800D01*
X855512Y-293267D01*
X855912Y-292600D01*
X856512Y-290467D01*
X857812Y-286067D01*
G01X854612D02*
X856512Y-290467D01*
G01X860712Y-294067D02*
X866712D01*
G01X872512Y-287133D02*
X872912Y-286733D01*
X873212Y-286067D01*
X873412Y-285133D01*
X873212Y-284333D01*
X872812Y-283800D01*
X872112Y-283400D01*
X869412D01*
Y-291400D01*
X872712D01*
X873412Y-290867D01*
X873812Y-290067D01*
X874012Y-289133D01*
X873812Y-288200D01*
X873212Y-287400D01*
X872512Y-287133D01*
X869412D01*
G01X877712Y-291400D02*
Y-283400D01*
X880112D01*
X880912Y-283800D01*
X881512Y-284733D01*
X881712Y-285800D01*
X881512Y-286867D01*
X881012Y-287667D01*
X880112Y-288067D01*
X877712D01*
G01X896912Y-334067D02*
X896312Y-333667D01*
X895612Y-333400D01*
X894812D01*
X893912Y-333800D01*
X893212Y-334467D01*
X892712Y-335267D01*
X892312Y-336600D01*
X892212Y-337800D01*
X892412Y-339000D01*
X892712Y-339800D01*
X893312Y-340600D01*
X894012Y-341133D01*
X894712Y-341400D01*
X895412D01*
X896112Y-341133D01*
X896712Y-340733D01*
X897212Y-340200D01*
G01X922212Y-341400D02*
Y-333400D01*
X921012Y-335000D01*
G01Y-341400D02*
X923412D01*
G01X928312Y-338067D02*
X929012Y-337133D01*
X929612Y-336600D01*
X930412Y-336333D01*
X931112Y-336600D01*
X931612Y-337133D01*
X932012Y-337933D01*
X932112Y-338867D01*
X932012Y-339667D01*
X931612Y-340467D01*
X931012Y-341133D01*
X930312Y-341400D01*
X929512Y-341133D01*
X928812Y-340334D01*
X928412Y-339133D01*
X928312Y-337800D01*
X928512Y-336067D01*
X928812Y-335133D01*
X929312Y-334200D01*
X930012Y-333533D01*
X930712Y-333400D01*
X931412Y-333667D01*
X931912Y-334333D01*
G01X1368938Y115666D02*
X1370811Y119413D01*
X1370542Y120218D01*
X1370005Y120486D01*
X1369773Y120602D01*
X1368079Y122297D01*
Y128437D01*
X1364216Y132300D01*
X1342042D01*
X1334879Y125137D01*
Y109284D01*
X1346500Y97663D01*
Y81900D01*
X1341489Y76889D01*
Y17610D01*
X1339221Y15342D01*
X1337379D01*
X1336733Y14696D01*
Y13386D01*
G01X1373938Y125666D02*
X1372063Y121917D01*
X1371258Y121650D01*
X1370721Y121918D01*
X1369679Y122960D01*
Y129100D01*
X1364879Y133900D01*
X1341379D01*
X1333279Y125800D01*
Y108621D01*
X1344900Y97000D01*
Y82563D01*
X1339889Y77552D01*
Y18273D01*
X1338558Y16942D01*
X1337379D01*
X1336733Y17588D01*
Y18898D01*
G01X1363938Y125666D02*
X1359472Y121200D01*
X1345679D01*
X1342679Y118200D01*
Y114000D01*
X1352079Y104600D01*
Y78600D01*
X1347479Y74000D01*
Y12563D01*
X1346740Y11824D01*
X1345255D01*
X1344607Y12472D01*
Y13780D01*
G01X1338938Y141650D02*
X1340811Y145397D01*
X1340542Y146202D01*
X1340539Y146204D01*
X1340344Y146301D01*
X1339836D01*
X1337700Y148437D01*
Y154200D01*
X1341700Y158200D01*
X1376579D01*
X1379579Y155200D01*
Y133700D01*
X1380579Y132700D01*
Y116616D01*
X1365000Y101037D01*
Y64200D01*
X1357200Y56400D01*
Y13000D01*
X1358376Y11824D01*
X1359724D01*
X1360355Y12455D01*
Y13780D01*
G01X1343938Y151650D02*
X1342063Y147901D01*
X1341258Y147634D01*
X1341252Y147636D01*
X1340721Y147901D01*
X1340499D01*
X1339300Y149100D01*
Y153537D01*
X1342363Y156600D01*
X1375916D01*
X1377979Y154537D01*
Y133037D01*
X1378979Y132037D01*
Y117279D01*
X1363400Y101700D01*
Y87818D01*
X1362800Y87218D01*
Y85418D01*
X1363400Y84818D01*
Y83018D01*
X1362800Y82418D01*
Y80618D01*
X1363400Y80018D01*
Y78218D01*
X1362800Y77618D01*
Y75818D01*
X1363400Y75218D01*
Y73418D01*
X1362800Y72818D01*
Y71018D01*
X1363400Y70418D01*
Y64863D01*
X1355600Y57063D01*
Y12337D01*
X1357713Y10224D01*
X1359800D01*
X1360355Y9669D01*
Y8268D01*
G01X1348938Y115666D02*
X1353645D01*
X1354679Y116700D01*
Y118800D01*
X1353879Y119600D01*
X1346342D01*
X1344279Y117537D01*
Y114663D01*
X1353679Y105263D01*
Y77937D01*
X1349079Y73337D01*
Y11900D01*
X1347403Y10224D01*
X1345379D01*
X1344607Y9452D01*
Y8268D01*
G54D15*
X306772Y67913D03*
X1176851D03*
G54D25*
G01X19088Y80158D02*
X14600Y84646D01*
Y94000D01*
X16900Y96300D01*
X22400D01*
X23300Y95400D01*
X57700D01*
X84800Y122500D01*
X107600D01*
X109400Y124300D01*
Y130700D01*
X111100Y132400D01*
X119700D01*
G01X19088Y91958D02*
X20530Y93400D01*
X58800D01*
X85670Y120270D01*
X115400D01*
G01X111958Y73600D02*
X109000Y76558D01*
Y85500D01*
X104900Y89600D01*
Y96100D01*
X109288Y100488D01*
Y103958D01*
G01Y92458D02*
Y88012D01*
X115200Y82100D01*
Y81800D01*
X116958Y80042D01*
Y68600D01*
G01X119288Y92458D02*
X115100Y96646D01*
Y106700D01*
X123600Y115200D01*
Y123500D01*
X117200Y129900D01*
X111500D01*
G01X119288Y103958D02*
X126358D01*
X132500Y110100D01*
G01X490276Y24803D02*
X492573Y27100D01*
X500300D01*
X502300Y29100D01*
Y60500D01*
X505200Y63400D01*
Y78800D01*
X519800Y93400D01*
X521200D01*
X525700Y97900D01*
Y99300D01*
G01X490276Y30315D02*
X493000Y33039D01*
Y55653D01*
X502500Y65153D01*
Y80000D01*
X518900Y96400D01*
X519400D01*
G01X701100Y16900D02*
X695900Y22100D01*
X686100D01*
X685590Y21590D01*
X679210D01*
X678800Y22000D01*
X668023D01*
X664921Y18898D01*
G01X1360355Y24803D02*
X1362752Y27200D01*
X1369800D01*
X1372300Y29700D01*
Y56500D01*
X1372950Y57150D01*
Y77250D01*
X1390400Y94700D01*
X1391800D01*
X1395200Y98100D01*
Y99500D01*
G01X1389900Y97600D02*
X1389200D01*
X1370400Y78800D01*
Y62100D01*
X1363100Y54800D01*
Y33060D01*
X1360355Y30315D01*
G01X1570800Y18900D02*
X1567700Y22000D01*
X1556300D01*
X1555890Y21590D01*
X1548110D01*
X1547600Y22100D01*
X1540400D01*
X1537198Y18898D01*
X1535000D01*
G54D16*
X343780Y19684D03*
Y27558D03*
X335906Y19684D03*
Y27558D03*
X343780Y43306D03*
Y51180D03*
X335906Y43306D03*
Y51180D03*
X343780Y59054D03*
X335906D03*
X1205984Y11810D03*
Y19684D03*
Y27558D03*
Y43306D03*
Y51180D03*
Y59054D03*
X1213858Y11810D03*
Y19684D03*
Y27558D03*
Y43306D03*
Y51180D03*
Y59054D03*
G54D17*
X383642Y158642D03*
X405964Y178327D03*
X439744D03*
X532934Y158642D03*
X555256Y178327D03*
X589036Y138957D03*
Y178327D03*
X1253721Y158642D03*
X1276043Y178327D03*
X1309823D03*
X1403012Y158642D03*
X1425334Y178327D03*
X1459114Y138957D03*
Y178327D03*
G54D18*
X466654Y18898D03*
Y13386D03*
X474528Y8268D03*
X490276D03*
Y30315D03*
Y24803D03*
X474528Y13780D03*
X490276D03*
X664921Y18898D03*
X1344607Y8268D03*
X1336733Y18898D03*
Y13386D03*
X1344607Y13780D03*
X1360355Y8268D03*
Y30315D03*
Y24803D03*
Y13780D03*
X1535000Y18898D03*
G54D19*
X468859Y141650D03*
X478859Y115666D03*
X473859Y151650D03*
X498859Y115666D03*
X503859Y125666D03*
X493859D03*
X1338938Y141650D03*
X1343938Y151650D03*
X1348938Y115666D03*
X1363938Y125666D03*
X1368938Y115666D03*
X1373938Y125666D03*
M02*
